FILE_TYPE = MACRO_DRAWING;
SET COLOR_WIRE YELLOW;
SET COLOR_PROP MONO;
SET COLOR_DOT WHITE;
SET COLOR_ARC YELLOW;
SET COLOR_BODY GREEN;
SET COLOR_NOTE MONO;
SET PROP_DISPLAY VALUE;
SET PAGE_NUMBER P221;
FORCEADD GND..1
(-650 -700);
FORCEPROP 3 LASTPIN (-650 -650) SIG_NAME GND\g
J 0
(-640 -640);
DISPLAY 0.659574 (-640 -640);
PAINT MONO (-640 -640);
DISPLAY INVISIBLE (-640 -640);
FORCEPROP 1 LAST HDL_POWER GND
J 0
(-650 -550);
DISPLAY 0.893617 (-650 -550);
PAINT GREEN (-650 -550);
DISPLAY INVISIBLE (-650 -550);
FORCEPROP 1 LAST BODY_TYPE PLUMBING
J 0
(-695 -743);
DISPLAY 0.340426 (-695 -743);
PAINT GREEN (-695 -743);
DISPLAY INVISIBLE (-695 -743);
FORCEPROP 1 LAST PATH I1
J 0
(-575 -700);
DISPLAY 0.872340 (-575 -700);
PAINT AQUA (-575 -700);
DISPLAY INVISIBLE (-575 -700);
FORCEPROP 1 LAST VOLTAGE 0.0V
J 0
(-695 -743);
DISPLAY 0.340426 (-695 -743);
PAINT SKYBLUE (-695 -743);
DISPLAY INVISIBLE (-695 -743);
FORCEPROP 1 LAST SIZE 1B
J 0
(-575 -750);
DISPLAY 0.893617 (-575 -750);
PAINT GREEN (-575 -750);
DISPLAY INVISIBLE (-575 -750);
FORCEPROP 2 LAST CDS_LIB mstr_symbols
J 0
(-650 -700);
PAINT MONO (-650 -700);
DISPLAY INVISIBLE (-650 -700);
FORCEADD GND..1
(50 700);
FORCEPROP 3 LASTPIN (50 750) SIG_NAME GND\g
J 0
(60 760);
DISPLAY 0.659574 (60 760);
PAINT MONO (60 760);
DISPLAY INVISIBLE (60 760);
FORCEPROP 1 LAST HDL_POWER GND
J 0
(50 850);
DISPLAY 0.872340 (50 850);
PAINT GREEN (50 850);
DISPLAY INVISIBLE (50 850);
FORCEPROP 1 LAST BODY_TYPE PLUMBING
J 0
(5 657);
DISPLAY 0.340426 (5 657);
PAINT GREEN (5 657);
DISPLAY INVISIBLE (5 657);
FORCEPROP 1 LAST PATH I10
J 0
(125 700);
DISPLAY 0.872340 (125 700);
PAINT AQUA (125 700);
DISPLAY INVISIBLE (125 700);
FORCEPROP 2 LAST CDS_LIB mstr_symbols
J 0
(50 700);
PAINT ORANGE (50 700);
DISPLAY INVISIBLE (50 700);
FORCEPROP 1 LAST VOLTAGE 0.0V
J 0
(5 657);
DISPLAY 0.340426 (5 657);
PAINT SKYBLUE (5 657);
DISPLAY INVISIBLE (5 657);
FORCEPROP 1 LAST SIZE 1B
J 0
(125 650);
DISPLAY 0.872340 (125 650);
PAINT AQUA (125 650);
DISPLAY INVISIBLE (125 650);
FORCEADD CAP..1
(50 925);
FORCEPROP 1 LASTPIN (50 825) $PN 2
J 0
(60 805);
DISPLAY 0.617021 (60 805);
PAINT ORANGE (60 805);
FORCEPROP 1 LAST PART_NUMBER E15431-003
J 0
(100 775);
DISPLAY 0.617021 (100 775);
PAINT BLUE (100 775);
FORCEPROP 1 LAST MATERIAL X6S
J 0
(100 825);
DISPLAY 0.617021 (100 825);
PAINT SKYBLUE (100 825);
FORCEPROP 1 LAST TOLERANCE 10%
J 0
(100 875);
DISPLAY 0.617021 (100 875);
PAINT SKYBLUE (100 875);
FORCEPROP 1 LAST VOLTAGE 6.3V
J 0
(100 925);
DISPLAY 0.617021 (100 925);
PAINT SKYBLUE (100 925);
FORCEPROP 1 LAST VALUE 4.7UF
J 0
(100 975);
DISPLAY 0.617021 (100 975);
PAINT SKYBLUE (100 975);
FORCEPROP 1 LAST LOCATION C6U12
J 0
(100 1025);
DISPLAY 0.617021 (100 1025);
PAINT AQUA (100 1025);
FORCEPROP 1 LASTPIN (50 1025) $PN 1
J 0
(60 1005);
DISPLAY 0.617021 (60 1005);
PAINT ORANGE (60 1005);
FORCEPROP 1 LAST PACK_TYPE 0603
J 0
(100 725);
DISPLAY 0.617021 (100 725);
PAINT SKYBLUE (100 725);
FORCEPROP 1 LAST PATH I11
J 0
(100 1075);
DISPLAY 0.978723 (100 1075);
PAINT WHITE (100 1075);
DISPLAY INVISIBLE (100 1075);
FORCEPROP 0 LAST CDS_SEC 1
J 0
(100 1075);
PAINT MONO (100 1075);
DISPLAY INVISIBLE (100 1075);
FORCEPROP 2 LAST CDS_LOCATION C6U12
J 0
(100 1025);
DISPLAY 0.617021 (100 1025);
PAINT AQUA (100 1025);
DISPLAY INVISIBLE (100 1025);
FORCEPROP 2 LAST SEC 1
J 0
(100 1125);
DISPLAY 0.680851 (100 1125);
PAINT MONO (100 1125);
DISPLAY INVISIBLE (100 1125);
FORCEPROP 2 LAST SEC_TYPE 0603
J 0
(100 1125);
DISPLAY 1.021277 (100 1125);
PAINT ORANGE (100 1125);
DISPLAY INVISIBLE (100 1125);
FORCEPROP 0 LAST ROOM VTT_ABC_PWR_VR
J 0
(100 1125);
DISPLAY 1.021277 (100 1125);
PAINT ORANGE (100 1125);
DISPLAY INVISIBLE (100 1125);
FORCEPROP 2 LAST CDS_LIB mstr_discrete
J 0
(50 925);
PAINT ORANGE (50 925);
DISPLAY INVISIBLE (50 925);
FORCEADD GND..1
(200 1175);
FORCEPROP 3 LASTPIN (200 1225) SIG_NAME GND\g
J 0
(210 1235);
DISPLAY 0.659574 (210 1235);
PAINT MONO (210 1235);
DISPLAY INVISIBLE (210 1235);
FORCEPROP 1 LAST HDL_POWER GND
J 0
(200 1325);
DISPLAY 0.893617 (200 1325);
PAINT GREEN (200 1325);
DISPLAY INVISIBLE (200 1325);
FORCEPROP 1 LAST BODY_TYPE PLUMBING
J 0
(155 1132);
DISPLAY 0.340426 (155 1132);
PAINT GREEN (155 1132);
DISPLAY INVISIBLE (155 1132);
FORCEPROP 1 LAST PATH I12
J 0
(275 1175);
DISPLAY 0.872340 (275 1175);
PAINT AQUA (275 1175);
DISPLAY INVISIBLE (275 1175);
FORCEPROP 1 LAST SIZE 1B
J 0
(275 1125);
DISPLAY 0.893617 (275 1125);
PAINT GREEN (275 1125);
DISPLAY INVISIBLE (275 1125);
FORCEPROP 2 LAST CDS_LIB mstr_symbols
J 0
(200 1175);
DISPLAY 0.744681 (200 1175);
PAINT MONO (200 1175);
DISPLAY INVISIBLE (200 1175);
FORCEPROP 1 LAST VOLTAGE 0.0V
J 0
(155 1132);
DISPLAY 0.340426 (155 1132);
PAINT SKYBLUE (155 1132);
DISPLAY INVISIBLE (155 1132);
FORCEADD CAP..1
(200 1400);
FORCEPROP 1 LAST TOLERANCE 10%
J 0
(250 1400);
DISPLAY 0.617021 (250 1400);
PAINT SKYBLUE (250 1400);
FORCEPROP 1 LAST MATERIAL X6S
J 0
(375 1400);
DISPLAY 0.617021 (375 1400);
PAINT SKYBLUE (375 1400);
FORCEPROP 1 LAST PART_NUMBER D97712-011
J 0
(250 1350);
DISPLAY 0.617021 (250 1350);
PAINT BLUE (250 1350);
FORCEPROP 1 LAST PACK_TYPE 0402
J 0
(250 1300);
DISPLAY 0.617021 (250 1300);
PAINT SKYBLUE (250 1300);
FORCEPROP 1 LASTPIN (200 1300) $PN 2
J 0
(210 1280);
DISPLAY 0.617021 (210 1280);
PAINT WHITE (210 1280);
FORCEPROP 1 LAST VOLTAGE 16V
J 0
(400 1450);
DISPLAY 0.617021 (400 1450);
PAINT SKYBLUE (400 1450);
FORCEPROP 1 LAST VALUE 1.0UF
J 0
(250 1450);
DISPLAY 0.617021 (250 1450);
PAINT SKYBLUE (250 1450);
FORCEPROP 1 LAST LOCATION C4G15
J 0
(250 1500);
DISPLAY 0.617021 (250 1500);
PAINT AQUA (250 1500);
FORCEPROP 1 LASTPIN (200 1500) $PN 1
J 0
(210 1480);
DISPLAY 0.617021 (210 1480);
PAINT WHITE (210 1480);
FORCEPROP 1 LAST PATH I13
J 0
(250 1550);
DISPLAY 0.978723 (250 1550);
PAINT WHITE (250 1550);
DISPLAY INVISIBLE (250 1550);
FORCEPROP 2 LAST BOM_COST MEM_VRD_VTT_ABC
J 0
(250 1600);
DISPLAY 1.021277 (250 1600);
PAINT ORANGE (250 1600);
DISPLAY INVISIBLE (250 1600);
FORCEPROP 2 LAST CDS_SEC 1
J 0
(250 1596);
DISPLAY 1.021277 (250 1596);
PAINT ORANGE (250 1596);
DISPLAY INVISIBLE (250 1596);
FORCEPROP 2 LAST $SEC 1
J 0
(250 1596);
DISPLAY 0.680851 (250 1596);
PAINT MONO (250 1596);
DISPLAY INVISIBLE (250 1596);
FORCEPROP 2 LAST CDS_LOCATION C4G15
J 0
(250 1500);
DISPLAY 0.617021 (250 1500);
PAINT AQUA (250 1500);
DISPLAY INVISIBLE (250 1500);
FORCEPROP 2 LAST ROOM VTT_ABC_PWR_VR
J 0
(250 1550);
DISPLAY 1.021277 (250 1550);
PAINT ORANGE (250 1550);
DISPLAY INVISIBLE (250 1550);
FORCEPROP 2 LAST CDS_LIB mstr_discrete
J 0
(200 1400);
PAINT ORANGE (200 1400);
DISPLAY INVISIBLE (200 1400);
FORCEADD RES..1
(-150 1675);
FORCEPROP 1 LAST PACK_TYPE 0402
J 0
(-225 1475);
DISPLAY 0.617021 (-225 1475);
PAINT SKYBLUE (-225 1475);
FORCEPROP 1 LAST MATERIAL CHIP
J 0
(-150 1525);
DISPLAY 0.617021 (-150 1525);
PAINT SKYBLUE (-150 1525);
FORCEPROP 1 LAST TOLERANCE 5%
J 0
(-150 1575);
DISPLAY 0.617021 (-150 1575);
PAINT SKYBLUE (-150 1575);
FORCEPROP 1 LAST VALUE 0.0
J 2
(-175 1575);
DISPLAY 0.617021 (-175 1575);
PAINT SKYBLUE (-175 1575);
FORCEPROP 1 LAST PART_NUMBER G21497-005
J 0
(-275 1625);
DISPLAY 0.617021 (-275 1625);
PAINT BLUE (-275 1625);
FORCEPROP 1 LAST WATTAGE 1/16W
J 2
(-175 1525);
DISPLAY 0.617021 (-175 1525);
PAINT SKYBLUE (-175 1525);
FORCEPROP 1 LAST LOCATION R6U4
J 0
(-200 1725);
DISPLAY 0.617021 (-200 1725);
PAINT AQUA (-200 1725);
FORCEPROP 1 LASTPIN (-50 1675) $PN 2
J 0
(-88 1687);
DISPLAY 0.617021 (-88 1687);
PAINT WHITE (-88 1687);
FORCEPROP 1 LASTPIN (-250 1675) $PN 1
J 0
(-238 1687);
DISPLAY 0.617021 (-238 1687);
PAINT WHITE (-238 1687);
FORCEPROP 1 LAST PATH I14
J 0
(-200 1825);
DISPLAY 0.978723 (-200 1825);
PAINT WHITE (-200 1825);
DISPLAY INVISIBLE (-200 1825);
FORCEPROP 0 LAST CDS_SEC 1
J 0
(-200 1775);
PAINT MONO (-200 1775);
DISPLAY INVISIBLE (-200 1775);
FORCEPROP 2 LAST ROOM VTT_ABC_PWR_VR
J 0
(-190 1760);
DISPLAY 1.021277 (-190 1760);
PAINT ORANGE (-190 1760);
DISPLAY INVISIBLE (-190 1760);
FORCEPROP 2 LAST SEC 1
J 0
(-184 1875);
DISPLAY 0.680851 (-184 1875);
PAINT MONO (-184 1875);
DISPLAY INVISIBLE (-184 1875);
FORCEPROP 2 LAST CDS_LOCATION R6U4
J 0
(-200 1725);
DISPLAY 0.617021 (-200 1725);
PAINT AQUA (-200 1725);
DISPLAY INVISIBLE (-200 1725);
FORCEPROP 2 LAST SEC_TYPE 0402
J 0
(-184 1875);
DISPLAY 1.021277 (-184 1875);
PAINT ORANGE (-184 1875);
DISPLAY INVISIBLE (-184 1875);
FORCEPROP 2 LAST BOM_COST MEM_VRD_VTT_ABC
J 0
(-190 1810);
DISPLAY 1.021277 (-190 1810);
PAINT ORANGE (-190 1810);
DISPLAY INVISIBLE (-190 1810);
FORCEPROP 2 LAST CDS_LIB mstr_discrete
J 0
(-150 1675);
DISPLAY 0.744681 (-150 1675);
PAINT MONO (-150 1675);
DISPLAY INVISIBLE (-150 1675);
FORCEADD MIC5166..1
(1275 975);
FORCEPROP 1 LAST PART_NUMBER H55101-001
J 0
(1025 575);
DISPLAY 0.617021 (1025 575);
PAINT BLUE (1025 575);
FORCEPROP 2 LASTPIN (975 875) $PN 6
J 2
(965 885);
DISPLAY 0.617021 (965 885);
PAINT ORANGE (965 885);
FORCEPROP 2 LASTPIN (1575 1125) $PN 1
J 0
(1585 1135);
DISPLAY 0.617021 (1585 1135);
PAINT ORANGE (1585 1135);
FORCEPROP 2 LASTPIN (1575 825) $PN 8
J 0
(1585 835);
DISPLAY 0.617021 (1585 835);
PAINT ORANGE (1585 835);
FORCEPROP 2 LASTPIN (975 725) $PN 2
J 2
(965 735);
DISPLAY 0.617021 (965 735);
PAINT ORANGE (965 735);
FORCEPROP 2 LASTPIN (1575 1225) $PN 9
J 0
(1585 1235);
DISPLAY 0.617021 (1585 1235);
PAINT ORANGE (1585 1235);
FORCEPROP 1 LAST LOCATION EU4G3
J 0
(1025 1400);
DISPLAY 0.617021 (1025 1400);
PAINT AQUA (1025 1400);
FORCEPROP 1 LAST MATERIAL IC
J 0
(1025 1350);
DISPLAY 0.617021 (1025 1350);
PAINT SKYBLUE (1025 1350);
FORCEPROP 2 LASTPIN (975 975) $PN 7
J 2
(965 985);
DISPLAY 0.617021 (965 985);
PAINT ORANGE (965 985);
FORCEPROP 2 LASTPIN (975 1075) $PN 4
J 2
(965 1085);
DISPLAY 0.617021 (965 1085);
PAINT ORANGE (965 1085);
FORCEPROP 2 LASTPIN (975 1225) $PN 10
J 2
(965 1235);
DISPLAY 0.617021 (965 1235);
PAINT ORANGE (965 1235);
FORCEPROP 2 LASTPIN (1575 925) $PN 5
J 0
(1585 935);
DISPLAY 0.617021 (1585 935);
PAINT ORANGE (1585 935);
FORCEPROP 2 LASTPIN (1575 775) $PN 3
J 0
(1585 785);
DISPLAY 0.617021 (1585 785);
PAINT ORANGE (1585 785);
FORCEPROP 2 LASTPIN (1575 675) $PN 11
J 0
(1585 685);
DISPLAY 0.617021 (1585 685);
PAINT ORANGE (1585 685);
FORCEPROP 1 LAST PATH I15
J 0
(1475 1350);
PAINT GREEN (1475 1350);
DISPLAY INVISIBLE (1475 1350);
FORCEPROP 0 LAST CDS_SEC 1
J 0
(1025 1450);
PAINT MONO (1025 1450);
DISPLAY INVISIBLE (1025 1450);
FORCEPROP 2 LAST CDS_LIB mstr_vreg
J 0
(1275 975);
PAINT ORANGE (1275 975);
DISPLAY INVISIBLE (1275 975);
FORCEPROP 1 LAST CDS_LMAN_SYM_OUTLINE -250,350,250,-350
J 0
(1275 975);
DISPLAY 0.468085 (1275 975);
PAINT GREEN (1275 975);
DISPLAY INVISIBLE (1275 975);
FORCEPROP 2 LAST BOM_COST MEM_VRD_VTT_ABC
J 0
(1025 1495);
DISPLAY 1.021277 (1025 1495);
PAINT ORANGE (1025 1495);
DISPLAY INVISIBLE (1025 1495);
FORCEPROP 1 LAST PACK_TYPE DFN
J 0
(1025 1450);
PAINT SKYBLUE (1025 1450);
DISPLAY INVISIBLE (1025 1450);
FORCEPROP 2 LAST ROOM VTT_ABC_PWR_VR
J 0
(1025 1447);
DISPLAY 1.021277 (1025 1447);
PAINT ORANGE (1025 1447);
DISPLAY INVISIBLE (1025 1447);
FORCEPROP 2 LAST SEC 1
J 0
(1025 1450);
DISPLAY 0.680851 (1025 1450);
PAINT MONO (1025 1450);
DISPLAY INVISIBLE (1025 1450);
FORCEPROP 2 LAST SEC_TYPE DFN
J 0
(1025 1450);
DISPLAY 1.021277 (1025 1450);
PAINT ORANGE (1025 1450);
DISPLAY INVISIBLE (1025 1450);
FORCEPROP 2 LAST CDS_LOCATION EU4G3
J 0
(1025 1400);
DISPLAY 0.617021 (1025 1400);
PAINT AQUA (1025 1400);
DISPLAY INVISIBLE (1025 1400);
FORCEADD GND..1
(1725 500);
FORCEPROP 3 LASTPIN (1725 550) SIG_NAME GND\g
J 0
(1735 560);
DISPLAY 0.659574 (1735 560);
PAINT MONO (1735 560);
DISPLAY INVISIBLE (1735 560);
FORCEPROP 1 LAST HDL_POWER GND
J 0
(1725 650);
DISPLAY 0.872340 (1725 650);
PAINT GREEN (1725 650);
DISPLAY INVISIBLE (1725 650);
FORCEPROP 1 LAST BODY_TYPE PLUMBING
J 0
(1680 457);
DISPLAY 0.340426 (1680 457);
PAINT GREEN (1680 457);
DISPLAY INVISIBLE (1680 457);
FORCEPROP 1 LAST PATH I16
J 0
(1800 500);
DISPLAY 0.872340 (1800 500);
PAINT AQUA (1800 500);
DISPLAY INVISIBLE (1800 500);
FORCEPROP 1 LAST SIZE 1B
J 0
(1800 450);
DISPLAY 0.872340 (1800 450);
PAINT AQUA (1800 450);
DISPLAY INVISIBLE (1800 450);
FORCEPROP 1 LAST VOLTAGE 0.0V
J 0
(1680 457);
DISPLAY 0.340426 (1680 457);
PAINT SKYBLUE (1680 457);
DISPLAY INVISIBLE (1680 457);
FORCEPROP 2 LAST CDS_LIB mstr_symbols
J 0
(1725 500);
PAINT ORANGE (1725 500);
DISPLAY INVISIBLE (1725 500);
FORCEADD GND..1
(-225 2025);
FORCEPROP 3 LASTPIN (-225 2075) SIG_NAME GND\g
J 0
(-215 2085);
DISPLAY 0.659574 (-215 2085);
PAINT MONO (-215 2085);
DISPLAY INVISIBLE (-215 2085);
FORCEPROP 1 LAST HDL_POWER GND
J 0
(-225 2175);
DISPLAY 0.893617 (-225 2175);
PAINT GREEN (-225 2175);
DISPLAY INVISIBLE (-225 2175);
FORCEPROP 1 LAST BODY_TYPE PLUMBING
J 0
(-270 1982);
DISPLAY 0.340426 (-270 1982);
PAINT GREEN (-270 1982);
DISPLAY INVISIBLE (-270 1982);
FORCEPROP 1 LAST PATH I17
J 0
(-150 2025);
DISPLAY 0.872340 (-150 2025);
PAINT AQUA (-150 2025);
DISPLAY INVISIBLE (-150 2025);
FORCEPROP 1 LAST VOLTAGE 0.0V
J 0
(-270 1982);
DISPLAY 0.340426 (-270 1982);
PAINT SKYBLUE (-270 1982);
DISPLAY INVISIBLE (-270 1982);
FORCEPROP 2 LAST CDS_LIB mstr_symbols
J 0
(-225 2025);
DISPLAY 0.744681 (-225 2025);
PAINT MONO (-225 2025);
DISPLAY INVISIBLE (-225 2025);
FORCEPROP 1 LAST SIZE 1B
J 0
(-150 1975);
DISPLAY 0.893617 (-150 1975);
PAINT GREEN (-150 1975);
DISPLAY INVISIBLE (-150 1975);
FORCEPROP 2 LAST ROOM VTT_ABC_PWR_VR
J 0
(-730 2105);
DISPLAY 1.021277 (-730 2105);
PAINT ORANGE (-730 2105);
DISPLAY INVISIBLE (-730 2105);
FORCEPROP 2 LAST BOM_COST MEM_VRD_VTT_ABC
J 0
(-730 2155);
DISPLAY 1.021277 (-730 2155);
PAINT ORANGE (-730 2155);
DISPLAY INVISIBLE (-730 2155);
FORCEADD CAP..1
(-225 2250);
FORCEPROP 1 LAST PACK_TYPE 0603LF
J 0
(-175 2050);
DISPLAY 0.617021 (-175 2050);
PAINT SKYBLUE (-175 2050);
FORCEPROP 1 LAST PART_NUMBER E15431-001
J 0
(-175 2100);
DISPLAY 0.617021 (-175 2100);
PAINT BLUE (-175 2100);
FORCEPROP 1 LAST MATERIAL X6S
J 0
(-175 2150);
DISPLAY 0.617021 (-175 2150);
PAINT SKYBLUE (-175 2150);
FORCEPROP 1 LAST TOLERANCE 20%
J 0
(-175 2200);
DISPLAY 0.617021 (-175 2200);
PAINT SKYBLUE (-175 2200);
FORCEPROP 1 LAST VOLTAGE 4V
J 0
(-175 2250);
DISPLAY 0.617021 (-175 2250);
PAINT SKYBLUE (-175 2250);
FORCEPROP 1 LAST VALUE 10UF
J 0
(-175 2300);
DISPLAY 0.617021 (-175 2300);
PAINT SKYBLUE (-175 2300);
FORCEPROP 1 LAST LOCATION C6U15
J 0
(-175 2350);
DISPLAY 0.617021 (-175 2350);
PAINT AQUA (-175 2350);
FORCEPROP 1 LASTPIN (-225 2350) $PN 1
J 0
(-215 2330);
DISPLAY 0.617021 (-215 2330);
PAINT WHITE (-215 2330);
FORCEPROP 1 LASTPIN (-225 2150) $PN 2
J 0
(-215 2130);
DISPLAY 0.617021 (-215 2130);
PAINT WHITE (-215 2130);
FORCEPROP 1 LAST PATH I18
J 0
(-175 2400);
DISPLAY 0.978723 (-175 2400);
PAINT WHITE (-175 2400);
DISPLAY INVISIBLE (-175 2400);
FORCEPROP 0 LAST CDS_SEC 1
J 0
(-175 2400);
PAINT MONO (-175 2400);
DISPLAY INVISIBLE (-175 2400);
FORCEPROP 2 LAST SEC 1
J 0
(-169 2465);
DISPLAY 0.680851 (-169 2465);
PAINT MONO (-169 2465);
DISPLAY INVISIBLE (-169 2465);
FORCEPROP 2 LAST SEC_TYPE 0603LF
J 0
(-169 2465);
DISPLAY 1.021277 (-169 2465);
PAINT ORANGE (-169 2465);
DISPLAY INVISIBLE (-169 2465);
FORCEPROP 2 LAST BOM_COST MEM_VRD_VTT_ABC
J 0
(-175 2450);
DISPLAY 1.021277 (-175 2450);
PAINT ORANGE (-175 2450);
DISPLAY INVISIBLE (-175 2450);
FORCEPROP 2 LAST ROOM VTT_ABC_PWR_VR
J 0
(-175 2400);
DISPLAY 1.021277 (-175 2400);
PAINT ORANGE (-175 2400);
DISPLAY INVISIBLE (-175 2400);
FORCEPROP 2 LAST CDS_LOCATION C6U15
J 0
(-175 2350);
DISPLAY 0.617021 (-175 2350);
PAINT AQUA (-175 2350);
DISPLAY INVISIBLE (-175 2350);
FORCEPROP 2 LAST CDS_LIB mstr_discrete
J 0
(-225 2250);
PAINT ORANGE (-225 2250);
DISPLAY INVISIBLE (-225 2250);
FORCEADD CAP..1
(200 2275);
FORCEPROP 1 LAST LOCATION C6U16
J 0
(250 2375);
DISPLAY 0.617021 (250 2375);
PAINT AQUA (250 2375);
FORCEPROP 1 LAST PACK_TYPE 0603LF
J 0
(250 2075);
DISPLAY 0.617021 (250 2075);
PAINT SKYBLUE (250 2075);
FORCEPROP 1 LAST PART_NUMBER E15431-001
J 0
(250 2125);
DISPLAY 0.617021 (250 2125);
PAINT BLUE (250 2125);
FORCEPROP 1 LAST MATERIAL X6S
J 0
(250 2175);
DISPLAY 0.617021 (250 2175);
PAINT SKYBLUE (250 2175);
FORCEPROP 1 LAST TOLERANCE 20%
J 0
(250 2225);
DISPLAY 0.617021 (250 2225);
PAINT SKYBLUE (250 2225);
FORCEPROP 1 LAST VOLTAGE 4V
J 0
(250 2275);
DISPLAY 0.617021 (250 2275);
PAINT SKYBLUE (250 2275);
FORCEPROP 1 LAST VALUE 10UF
J 0
(250 2325);
DISPLAY 0.617021 (250 2325);
PAINT SKYBLUE (250 2325);
FORCEPROP 1 LASTPIN (200 2375) $PN 1
J 0
(210 2355);
DISPLAY 0.617021 (210 2355);
PAINT WHITE (210 2355);
FORCEPROP 1 LASTPIN (200 2175) $PN 2
J 0
(210 2155);
DISPLAY 0.617021 (210 2155);
PAINT WHITE (210 2155);
FORCEPROP 1 LAST PATH I19
J 0
(250 2425);
DISPLAY 0.978723 (250 2425);
PAINT WHITE (250 2425);
DISPLAY INVISIBLE (250 2425);
FORCEPROP 0 LAST CDS_SEC 1
J 0
(250 2425);
PAINT MONO (250 2425);
DISPLAY INVISIBLE (250 2425);
FORCEPROP 2 LAST SEC_TYPE 0603LF
J 0
(256 2490);
DISPLAY 1.021277 (256 2490);
PAINT ORANGE (256 2490);
DISPLAY INVISIBLE (256 2490);
FORCEPROP 2 LAST SEC 1
J 0
(256 2490);
DISPLAY 0.680851 (256 2490);
PAINT MONO (256 2490);
DISPLAY INVISIBLE (256 2490);
FORCEPROP 2 LAST BOM_COST MEM_VRD_VTT_ABC
J 0
(250 2475);
DISPLAY 1.021277 (250 2475);
PAINT ORANGE (250 2475);
DISPLAY INVISIBLE (250 2475);
FORCEPROP 2 LAST CDS_LOCATION C6U16
J 0
(250 2375);
DISPLAY 0.617021 (250 2375);
PAINT AQUA (250 2375);
DISPLAY INVISIBLE (250 2375);
FORCEPROP 2 LAST ROOM VTT_ABC_PWR_VR
J 0
(250 2425);
DISPLAY 1.021277 (250 2425);
PAINT ORANGE (250 2425);
DISPLAY INVISIBLE (250 2425);
FORCEPROP 2 LAST CDS_LIB mstr_discrete
J 0
(200 2275);
PAINT ORANGE (200 2275);
DISPLAY INVISIBLE (200 2275);
FORCEADD CAP..1
R 2
(-650 -475);
FORCEPROP 1 LAST PART_NUMBER A36096-046
J 2
(-700 -625);
DISPLAY 0.659574 (-700 -625);
PAINT BLUE (-700 -625);
FORCEPROP 1 LAST VOLTAGE 50V
J 2
(-700 -475);
DISPLAY 0.617021 (-700 -475);
PAINT SKYBLUE (-700 -475);
FORCEPROP 1 LAST TOLERANCE 10%
J 2
(-775 -525);
DISPLAY 0.617021 (-775 -525);
PAINT SKYBLUE (-775 -525);
FORCEPROP 1 LAST VALUE 1000PF
J 2
(-700 -425);
DISPLAY 0.617021 (-700 -425);
PAINT SKYBLUE (-700 -425);
FORCEPROP 1 LAST PACK_TYPE 0402LF
J 2
(-925 -525);
DISPLAY 0.617021 (-925 -525);
PAINT SKYBLUE (-925 -525);
FORCEPROP 1 LAST MATERIAL EMPTY
J 2
(-700 -575);
DISPLAY 0.617021 (-700 -575);
PAINT RED (-700 -575);
FORCEPROP 1 LAST LOCATION C4G23
J 2
(-700 -375);
DISPLAY 0.617021 (-700 -375);
PAINT AQUA (-700 -375);
FORCEPROP 1 LASTPIN (-650 -375) $PN 1
J 2
(-660 -395);
DISPLAY 0.617021 (-660 -395);
PAINT WHITE (-660 -395);
FORCEPROP 1 LASTPIN (-650 -575) $PN 2
J 2
(-660 -595);
DISPLAY 0.617021 (-660 -595);
PAINT WHITE (-660 -595);
FORCEPROP 1 LAST PATH I2
J 2
(-700 -325);
DISPLAY 0.978723 (-700 -325);
PAINT WHITE (-700 -325);
DISPLAY INVISIBLE (-700 -325);
FORCEPROP 0 LAST CDS_SEC 1
J 0
(-700 -325);
PAINT MONO (-700 -325);
DISPLAY INVISIBLE (-700 -325);
FORCEPROP 2 LAST ROOM VTT_ABC_PWR_VR
J 0
(-685 -320);
DISPLAY 1.021277 (-685 -320);
PAINT ORANGE (-685 -320);
DISPLAY INVISIBLE (-685 -320);
FORCEPROP 2 LAST SEC 1
J 0
(-679 -255);
DISPLAY 0.680851 (-679 -255);
PAINT MONO (-679 -255);
DISPLAY INVISIBLE (-679 -255);
FORCEPROP 2 LAST SEC_TYPE 0402LF
J 0
(-679 -255);
DISPLAY 1.021277 (-679 -255);
PAINT ORANGE (-679 -255);
DISPLAY INVISIBLE (-679 -255);
FORCEPROP 2 LAST BOM_COST MEM_VRD_VTT_ABC
J 0
(-685 -270);
DISPLAY 1.021277 (-685 -270);
PAINT ORANGE (-685 -270);
DISPLAY INVISIBLE (-685 -270);
FORCEPROP 2 LAST CDS_LIB mstr_discrete
J 0
(-650 -475);
PAINT ORANGE (-650 -475);
DISPLAY INVISIBLE (-650 -475);
FORCEPROP 2 LAST CDS_LOCATION C4G23
J 2
(-700 -375);
DISPLAY 0.617021 (-700 -375);
PAINT AQUA (-700 -375);
DISPLAY INVISIBLE (-700 -375);
FORCEADD GND..1
(200 2025);
FORCEPROP 3 LASTPIN (200 2075) SIG_NAME GND\g
J 0
(210 2085);
DISPLAY 0.659574 (210 2085);
PAINT MONO (210 2085);
DISPLAY INVISIBLE (210 2085);
FORCEPROP 1 LAST HDL_POWER GND
J 0
(200 2175);
DISPLAY 0.893617 (200 2175);
PAINT GREEN (200 2175);
DISPLAY INVISIBLE (200 2175);
FORCEPROP 1 LAST BODY_TYPE PLUMBING
J 0
(155 1982);
DISPLAY 0.340426 (155 1982);
PAINT GREEN (155 1982);
DISPLAY INVISIBLE (155 1982);
FORCEPROP 1 LAST PATH I20
J 0
(275 2025);
DISPLAY 0.872340 (275 2025);
PAINT AQUA (275 2025);
DISPLAY INVISIBLE (275 2025);
FORCEPROP 1 LAST SIZE 1B
J 0
(275 1975);
DISPLAY 0.893617 (275 1975);
PAINT GREEN (275 1975);
DISPLAY INVISIBLE (275 1975);
FORCEPROP 1 LAST VOLTAGE 0.0V
J 0
(155 1982);
DISPLAY 0.340426 (155 1982);
PAINT SKYBLUE (155 1982);
DISPLAY INVISIBLE (155 1982);
FORCEPROP 2 LAST CDS_LIB mstr_symbols
J 0
(200 2025);
PAINT MONO (200 2025);
DISPLAY INVISIBLE (200 2025);
FORCEPROP 2 LAST ROOM VTT_ABC_PWR_VR
J 0
(-305 2105);
DISPLAY 1.021277 (-305 2105);
PAINT ORANGE (-305 2105);
DISPLAY INVISIBLE (-305 2105);
FORCEPROP 2 LAST BOM_COST MEM_VRD_VTT_ABC
J 0
(-305 2155);
DISPLAY 1.021277 (-305 2155);
PAINT ORANGE (-305 2155);
DISPLAY INVISIBLE (-305 2155);
FORCEADD GND..1
(2100 500);
FORCEPROP 3 LASTPIN (2100 550) SIG_NAME GND\g
J 0
(2110 560);
DISPLAY 0.659574 (2110 560);
PAINT MONO (2110 560);
DISPLAY INVISIBLE (2110 560);
FORCEPROP 1 LAST HDL_POWER GND
J 0
(2100 650);
DISPLAY 0.872340 (2100 650);
PAINT GREEN (2100 650);
DISPLAY INVISIBLE (2100 650);
FORCEPROP 1 LAST BODY_TYPE PLUMBING
J 0
(2055 457);
DISPLAY 0.340426 (2055 457);
PAINT GREEN (2055 457);
DISPLAY INVISIBLE (2055 457);
FORCEPROP 1 LAST PATH I21
J 0
(2175 500);
DISPLAY 0.872340 (2175 500);
PAINT AQUA (2175 500);
DISPLAY INVISIBLE (2175 500);
FORCEPROP 1 LAST SIZE 1B
J 0
(2175 450);
DISPLAY 0.872340 (2175 450);
PAINT AQUA (2175 450);
DISPLAY INVISIBLE (2175 450);
FORCEPROP 1 LAST VOLTAGE 0.0V
J 0
(2055 457);
DISPLAY 0.340426 (2055 457);
PAINT SKYBLUE (2055 457);
DISPLAY INVISIBLE (2055 457);
FORCEPROP 2 LAST CDS_LIB mstr_symbols
J 0
(2100 500);
PAINT ORANGE (2100 500);
DISPLAY INVISIBLE (2100 500);
FORCEADD CAP..1
(2100 750);
FORCEPROP 1 LAST PART_NUMBER D97712-011
J 0
(2150 700);
DISPLAY 0.617021 (2150 700);
PAINT BLUE (2150 700);
FORCEPROP 1 LAST PACK_TYPE 0402
J 0
(2150 650);
DISPLAY 0.617021 (2150 650);
PAINT SKYBLUE (2150 650);
FORCEPROP 1 LAST TOLERANCE 10%
J 0
(2150 750);
DISPLAY 0.617021 (2150 750);
PAINT SKYBLUE (2150 750);
FORCEPROP 1 LAST VALUE 1.0UF
J 0
(2150 800);
DISPLAY 0.617021 (2150 800);
PAINT SKYBLUE (2150 800);
FORCEPROP 1 LAST VOLTAGE 16V
J 0
(2300 800);
DISPLAY 0.617021 (2300 800);
PAINT SKYBLUE (2300 800);
FORCEPROP 1 LAST MATERIAL X6S
J 0
(2275 750);
DISPLAY 0.617021 (2275 750);
PAINT SKYBLUE (2275 750);
FORCEPROP 1 LAST LOCATION C4G16
J 0
(2150 850);
DISPLAY 0.617021 (2150 850);
PAINT AQUA (2150 850);
FORCEPROP 1 LASTPIN (2100 850) $PN 1
J 0
(2110 830);
DISPLAY 0.617021 (2110 830);
PAINT WHITE (2110 830);
FORCEPROP 1 LASTPIN (2100 650) $PN 2
J 0
(2110 630);
DISPLAY 0.617021 (2110 630);
PAINT WHITE (2110 630);
FORCEPROP 1 LAST PATH I22
J 0
(2150 900);
DISPLAY 0.978723 (2150 900);
PAINT WHITE (2150 900);
DISPLAY INVISIBLE (2150 900);
FORCEPROP 0 LAST CDS_SEC 1
J 0
(2150 900);
PAINT MONO (2150 900);
DISPLAY INVISIBLE (2150 900);
FORCEPROP 2 LAST SEC_TYPE 0402
J 0
(2156 965);
DISPLAY 1.021277 (2156 965);
PAINT ORANGE (2156 965);
DISPLAY INVISIBLE (2156 965);
FORCEPROP 2 LAST BOM_COST MEM_VRD_VTT_ABC
J 0
(2150 950);
DISPLAY 1.021277 (2150 950);
PAINT ORANGE (2150 950);
DISPLAY INVISIBLE (2150 950);
FORCEPROP 2 LAST SEC 1
J 0
(2156 965);
DISPLAY 0.680851 (2156 965);
PAINT MONO (2156 965);
DISPLAY INVISIBLE (2156 965);
FORCEPROP 2 LAST ROOM VTT_ABC_PWR_VR
J 0
(2150 900);
DISPLAY 1.021277 (2150 900);
PAINT ORANGE (2150 900);
DISPLAY INVISIBLE (2150 900);
FORCEPROP 2 LAST CDS_LOCATION C4G16
J 0
(2150 850);
DISPLAY 0.617021 (2150 850);
PAINT AQUA (2150 850);
DISPLAY INVISIBLE (2150 850);
FORCEPROP 2 LAST CDS_LIB mstr_discrete
J 0
(2100 750);
PAINT ORANGE (2100 750);
DISPLAY INVISIBLE (2100 750);
FORCEADD GND..1
(3700 525);
FORCEPROP 3 LASTPIN (3700 575) SIG_NAME GND\g
J 0
(3710 585);
DISPLAY 0.659574 (3710 585);
PAINT MONO (3710 585);
DISPLAY INVISIBLE (3710 585);
FORCEPROP 1 LAST HDL_POWER GND
J 0
(3700 675);
DISPLAY 0.893617 (3700 675);
PAINT GREEN (3700 675);
DISPLAY INVISIBLE (3700 675);
FORCEPROP 1 LAST BODY_TYPE PLUMBING
J 0
(3655 482);
DISPLAY 0.340426 (3655 482);
PAINT GREEN (3655 482);
DISPLAY INVISIBLE (3655 482);
FORCEPROP 1 LAST PATH I23
J 0
(3775 525);
DISPLAY 0.872340 (3775 525);
PAINT AQUA (3775 525);
DISPLAY INVISIBLE (3775 525);
FORCEPROP 1 LAST VOLTAGE 0.0V
J 0
(3655 482);
DISPLAY 0.340426 (3655 482);
PAINT SKYBLUE (3655 482);
DISPLAY INVISIBLE (3655 482);
FORCEPROP 1 LAST SIZE 1B
J 0
(3775 475);
DISPLAY 0.893617 (3775 475);
PAINT GREEN (3775 475);
DISPLAY INVISIBLE (3775 475);
FORCEPROP 2 LAST CDS_LIB mstr_symbols
J 0
(3700 525);
PAINT ORANGE (3700 525);
DISPLAY INVISIBLE (3700 525);
FORCEADD CAP..1
(3700 950);
FORCEPROP 0 LAST GROUP PWR_MLCC_CAP
J 0
(3756 762);
DISPLAY 0.638298 (3756 762);
PAINT BROWN (3756 762);
DISPLAY BOTH (3756 762);
FORCEPROP 1 LAST VALUE 22UF
J 0
(3750 1000);
DISPLAY 0.617021 (3750 1000);
PAINT SKYBLUE (3750 1000);
FORCEPROP 1 LAST LOCATION C4G24
J 0
(3750 1050);
DISPLAY 0.617021 (3750 1050);
PAINT AQUA (3750 1050);
FORCEPROP 1 LAST VOLTAGE 4V
J 0
(3750 950);
DISPLAY 0.617021 (3750 950);
PAINT SKYBLUE (3750 950);
FORCEPROP 1 LAST PACK_TYPE 0805LF
J 0
(3750 800);
DISPLAY 0.617021 (3750 800);
PAINT SKYBLUE (3750 800);
FORCEPROP 1 LAST MATERIAL X6S
J 0
(3750 850);
DISPLAY 0.617021 (3750 850);
PAINT SKYBLUE (3750 850);
FORCEPROP 1 LAST TOLERANCE 20%
J 0
(3750 900);
DISPLAY 0.617021 (3750 900);
PAINT SKYBLUE (3750 900);
FORCEPROP 1 LASTPIN (3700 1050) $PN 1
J 0
(3710 1030);
DISPLAY 0.617021 (3710 1030);
PAINT WHITE (3710 1030);
FORCEPROP 1 LASTPIN (3700 850) $PN 2
J 0
(3710 830);
DISPLAY 0.617021 (3710 830);
PAINT WHITE (3710 830);
FORCEPROP 1 LAST PART_NUMBER C95333-002
R 1
J 0
(3650 800);
DISPLAY 0.617021 (3650 800);
PAINT BLUE (3650 800);
FORCEPROP 1 LAST PATH I24
J 0
(3750 1100);
DISPLAY 0.978723 (3750 1100);
PAINT WHITE (3750 1100);
DISPLAY INVISIBLE (3750 1100);
FORCEPROP 0 LAST CDS_SEC 1
J 0
(3750 1100);
PAINT MONO (3750 1100);
DISPLAY INVISIBLE (3750 1100);
FORCEPROP 2 LAST SEC_TYPE 0805LF
J 0
(3751 1170);
DISPLAY 1.021277 (3751 1170);
PAINT ORANGE (3751 1170);
DISPLAY INVISIBLE (3751 1170);
FORCEPROP 2 LAST ROOM VTT_ABC_PWR_VR
J 0
(3770 1105);
DISPLAY 1.021277 (3770 1105);
PAINT ORANGE (3770 1105);
DISPLAY INVISIBLE (3770 1105);
FORCEPROP 2 LAST CDS_LOCATION C4G24
J 0
(3750 1050);
DISPLAY 0.617021 (3750 1050);
PAINT AQUA (3750 1050);
DISPLAY INVISIBLE (3750 1050);
FORCEPROP 2 LAST SEC 1
J 0
(3751 1170);
DISPLAY 0.680851 (3751 1170);
PAINT MONO (3751 1170);
DISPLAY INVISIBLE (3751 1170);
FORCEPROP 2 LAST CDS_LIB mstr_discrete
J 0
(3700 950);
PAINT ORANGE (3700 950);
DISPLAY INVISIBLE (3700 950);
FORCEPROP 2 LAST BOM_COST MEM_VRD_VTT_ABC
J 0
(3770 1155);
DISPLAY 1.021277 (3770 1155);
PAINT ORANGE (3770 1155);
DISPLAY INVISIBLE (3770 1155);
FORCEADD RES..2
(3225 2000);
FORCEPROP 1 LAST MATERIAL CHIP
J 0
(3265 1925);
DISPLAY 0.617021 (3265 1925);
PAINT SKYBLUE (3265 1925);
FORCEPROP 1 LAST WATTAGE 1/16W
J 0
(3265 1975);
DISPLAY 0.617021 (3265 1975);
PAINT SKYBLUE (3265 1975);
FORCEPROP 1 LAST TOLERANCE 1%
J 0
(3270 2025);
DISPLAY 0.617021 (3270 2025);
PAINT SKYBLUE (3270 2025);
FORCEPROP 1 LASTPIN (3225 1900) $PN 2
J 0
(3230 1910);
DISPLAY 0.617021 (3230 1910);
PAINT ORANGE (3230 1910);
FORCEPROP 1 LASTPIN (3225 2100) $PN 1
J 0
(3230 2062);
DISPLAY 0.617021 (3230 2062);
PAINT ORANGE (3230 2062);
FORCEPROP 1 LAST VALUE 10.0K
J 0
(3270 2075);
DISPLAY 0.617021 (3270 2075);
PAINT SKYBLUE (3270 2075);
FORCEPROP 1 LAST LOCATION R4G18
J 0
(3270 2125);
DISPLAY 0.617021 (3270 2125);
PAINT AQUA (3270 2125);
FORCEPROP 1 LAST PACK_TYPE 0402
J 0
(3265 1825);
DISPLAY 0.617021 (3265 1825);
PAINT SKYBLUE (3265 1825);
FORCEPROP 1 LAST PART_NUMBER G21796-016
J 0
(3265 1875);
DISPLAY 0.617021 (3265 1875);
PAINT BLUE (3265 1875);
FORCEPROP 1 LAST PATH I25
J 0
(3275 2175);
DISPLAY 0.978723 (3275 2175);
PAINT WHITE (3275 2175);
DISPLAY INVISIBLE (3275 2175);
FORCEPROP 0 LAST CDS_SEC 1
J 0
(3275 2175);
PAINT MONO (3275 2175);
DISPLAY INVISIBLE (3275 2175);
FORCEPROP 2 LAST CDS_LIB mstr_discrete
J 0
(3225 2000);
PAINT ORANGE (3225 2000);
DISPLAY INVISIBLE (3225 2000);
FORCEPROP 2 LAST CDS_LOCATION R4G18
J 0
(3270 2125);
DISPLAY 0.617021 (3270 2125);
PAINT AQUA (3270 2125);
DISPLAY INVISIBLE (3270 2125);
FORCEPROP 0 LAST ROOM VTT_ABC_PWR_VR
J 0
(3270 2219);
DISPLAY 1.021277 (3270 2219);
PAINT ORANGE (3270 2219);
DISPLAY INVISIBLE (3270 2219);
FORCEPROP 2 LAST SEC 1
J 0
(3275 2225);
PAINT MONO (3275 2225);
DISPLAY INVISIBLE (3275 2225);
FORCEPROP 2 LAST SEC_TYPE 0402
J 0
(3275 2225);
DISPLAY 1.021277 (3275 2225);
PAINT ORANGE (3275 2225);
DISPLAY INVISIBLE (3275 2225);
FORCEPROP 0 LAST BOM_COST MEM_VRD_VTT_ABC
J 0
(3270 2219);
DISPLAY 1.021277 (3270 2219);
PAINT ORANGE (3270 2219);
DISPLAY INVISIBLE (3270 2219);
FORCEADD P3V3..1
(3225 2200);
FORCEPROP 3 LASTPIN (3225 2150) SIG_NAME P3V3\g
J 0
(3235 2160);
DISPLAY 0.659574 (3235 2160);
PAINT MONO (3235 2160);
DISPLAY INVISIBLE (3235 2160);
FORCEPROP 1 LAST HDL_POWER P3V3
J 0
(2900 2075);
DISPLAY 0.872340 (2900 2075);
PAINT ORANGE (2900 2075);
DISPLAY INVISIBLE (2900 2075);
FORCEPROP 1 LAST BODY_TYPE PLUMBING
J 0
(3180 2157);
DISPLAY 0.340426 (3180 2157);
PAINT GREEN (3180 2157);
DISPLAY INVISIBLE (3180 2157);
FORCEPROP 1 LAST PATH I26
J 0
(3270 2202);
DISPLAY 0.340426 (3270 2202);
PAINT GREEN (3270 2202);
DISPLAY INVISIBLE (3270 2202);
FORCEPROP 2 LAST CDS_LIB mstr_symbols
J 0
(3225 2200);
PAINT ORANGE (3225 2200);
DISPLAY INVISIBLE (3225 2200);
FORCEPROP 1 LAST SIZE 1B
J 0
(3270 2222);
DISPLAY 0.340426 (3270 2222);
PAINT GREEN (3270 2222);
DISPLAY INVISIBLE (3270 2222);
FORCEPROP 1 LAST VOLTAGE 3.3V
J 0
(3180 2157);
DISPLAY 0.340426 (3180 2157);
PAINT SKYBLUE (3180 2157);
DISPLAY INVISIBLE (3180 2157);
FORCEADD PVTT_ABC..1
(3325 3650);
FORCEPROP 3 LASTPIN (3325 3600) SIG_NAME PVTT_ABC\g
J 0
(3335 3610);
DISPLAY 0.659574 (3335 3610);
PAINT MONO (3335 3610);
DISPLAY INVISIBLE (3335 3610);
FORCEPROP 1 LAST HDL_POWER PVTT_ABC
J 1
(3325 3700);
DISPLAY 0.872340 (3325 3700);
PAINT GREEN (3325 3700);
DISPLAY INVISIBLE (3325 3700);
FORCEPROP 1 LAST BODY_TYPE PLUMBING
J 0
(3280 3607);
DISPLAY 0.340426 (3280 3607);
PAINT GREEN (3280 3607);
DISPLAY INVISIBLE (3280 3607);
FORCEPROP 1 LAST PATH I28
J 0
(3375 3675);
DISPLAY 0.872340 (3375 3675);
PAINT AQUA (3375 3675);
DISPLAY INVISIBLE (3375 3675);
FORCEPROP 2 LAST ROOM VTT_ABC_PWR_VR
J 0
(3575 3750);
PAINT ORANGE (3575 3750);
DISPLAY INVISIBLE (3575 3750);
FORCEPROP 2 LAST BOM_COST MEM_VRD_PVDDQ_AB
J 0
(3400 3750);
PAINT MONO (3400 3750);
DISPLAY INVISIBLE (3400 3750);
FORCEPROP 2 LAST CDS_LIB mstr_symbols
J 0
(3325 3650);
PAINT ORANGE (3325 3650);
DISPLAY INVISIBLE (3325 3650);
FORCEPROP 1 LAST VOLTAGE 0.6V
J 0
(3280 3607);
DISPLAY 0.340426 (3280 3607);
PAINT SKYBLUE (3280 3607);
DISPLAY INVISIBLE (3280 3607);
FORCEADD OFFPAGE..1
(-1675 50);
FORCEPROP 2 LAST $XR0 215 
J 0
(-1927 50);
DISPLAY 0.638298 (-1927 50);
PAINT MONO (-1927 50);
FORCEPROP 1 LAST COMMENT_BODY TRUE
J 0
(-1550 -50);
DISPLAY 0.872340 (-1550 -50);
PAINT GREEN (-1550 -50);
DISPLAY INVISIBLE (-1550 -50);
FORCEPROP 1 LAST OFFPAGE TRUE
J 0
(-1350 -75);
DISPLAY 0.872340 (-1350 -75);
PAINT GREEN (-1350 -75);
DISPLAY INVISIBLE (-1350 -75);
FORCEPROP 2 LAST PATH I3
J 0
(-1925 100);
DISPLAY 1.021277 (-1925 100);
PAINT ORANGE (-1925 100);
DISPLAY INVISIBLE (-1925 100);
FORCEPROP 2 LAST CDS_LIB mstr_standard
J 0
(-1675 50);
DISPLAY 0.744681 (-1675 50);
PAINT MONO (-1675 50);
DISPLAY INVISIBLE (-1675 50);
FORCEADD CAP..1
(3850 1525);
FORCEPROP 1 LAST PART_NUMBER A36096-046
J 0
(3900 1375);
DISPLAY 0.617021 (3900 1375);
PAINT BLUE (3900 1375);
FORCEPROP 1 LAST TOLERANCE 10%
J 0
(3900 1475);
DISPLAY 0.617021 (3900 1475);
PAINT SKYBLUE (3900 1475);
FORCEPROP 1 LAST LOCATION C4G14
J 0
(3900 1625);
DISPLAY 0.617021 (3900 1625);
PAINT AQUA (3900 1625);
FORCEPROP 1 LAST MATERIAL X7R
J 0
(3900 1425);
DISPLAY 0.617021 (3900 1425);
PAINT SKYBLUE (3900 1425);
FORCEPROP 1 LAST VOLTAGE 50V
J 0
(3900 1525);
DISPLAY 0.617021 (3900 1525);
PAINT SKYBLUE (3900 1525);
FORCEPROP 1 LAST VALUE 1000PF
J 0
(3900 1575);
DISPLAY 0.617021 (3900 1575);
PAINT SKYBLUE (3900 1575);
FORCEPROP 1 LASTPIN (3850 1625) $PN 1
J 0
(3860 1605);
DISPLAY 0.617021 (3860 1605);
PAINT WHITE (3860 1605);
FORCEPROP 1 LASTPIN (3850 1425) $PN 2
J 0
(3860 1405);
DISPLAY 0.617021 (3860 1405);
PAINT WHITE (3860 1405);
FORCEPROP 1 LAST PACK_TYPE 0402LF
J 0
(3900 1325);
DISPLAY 0.617021 (3900 1325);
PAINT SKYBLUE (3900 1325);
FORCEPROP 1 LAST PATH I30
J 0
(3900 1675);
DISPLAY 0.978723 (3900 1675);
PAINT WHITE (3900 1675);
DISPLAY INVISIBLE (3900 1675);
FORCEPROP 0 LAST CDS_SEC 1
J 0
(3900 1675);
PAINT MONO (3900 1675);
DISPLAY INVISIBLE (3900 1675);
FORCEPROP 2 LAST CDS_LIB mstr_discrete
J 0
(3850 1525);
DISPLAY 0.744681 (3850 1525);
PAINT MONO (3850 1525);
DISPLAY INVISIBLE (3850 1525);
FORCEPROP 2 LAST CDS_LOCATION C4G14
J 0
(3900 1625);
DISPLAY 0.617021 (3900 1625);
PAINT AQUA (3900 1625);
DISPLAY INVISIBLE (3900 1625);
FORCEPROP 2 LAST ROOM VTT_ABC_PWR_VR
J 0
(3900 1675);
DISPLAY 1.021277 (3900 1675);
PAINT ORANGE (3900 1675);
DISPLAY INVISIBLE (3900 1675);
FORCEPROP 2 LAST BOM_COST MEM_VRD_VTT_ABC
J 0
(3900 1725);
DISPLAY 1.021277 (3900 1725);
PAINT ORANGE (3900 1725);
DISPLAY INVISIBLE (3900 1725);
FORCEPROP 2 LAST SEC_TYPE 0402LF
J 0
(3900 1725);
DISPLAY 1.021277 (3900 1725);
PAINT ORANGE (3900 1725);
DISPLAY INVISIBLE (3900 1725);
FORCEPROP 2 LAST SEC 1
J 0
(3900 1725);
DISPLAY 0.680851 (3900 1725);
PAINT MONO (3900 1725);
DISPLAY INVISIBLE (3900 1725);
FORCEADD GND..1
(3850 1300);
FORCEPROP 3 LASTPIN (3850 1350) SIG_NAME GND\g
J 0
(3860 1360);
DISPLAY 0.659574 (3860 1360);
PAINT MONO (3860 1360);
DISPLAY INVISIBLE (3860 1360);
FORCEPROP 1 LAST HDL_POWER GND
J 0
(3850 1450);
DISPLAY 0.893617 (3850 1450);
PAINT GREEN (3850 1450);
DISPLAY INVISIBLE (3850 1450);
FORCEPROP 1 LAST BODY_TYPE PLUMBING
J 0
(3805 1257);
DISPLAY 0.340426 (3805 1257);
PAINT GREEN (3805 1257);
DISPLAY INVISIBLE (3805 1257);
FORCEPROP 1 LAST PATH I32
J 0
(3925 1300);
DISPLAY 0.872340 (3925 1300);
PAINT AQUA (3925 1300);
DISPLAY INVISIBLE (3925 1300);
FORCEPROP 1 LAST VOLTAGE 0.0V
J 0
(3805 1257);
DISPLAY 0.340426 (3805 1257);
PAINT SKYBLUE (3805 1257);
DISPLAY INVISIBLE (3805 1257);
FORCEPROP 2 LAST CDS_LIB mstr_symbols
J 0
(3850 1300);
DISPLAY 0.744681 (3850 1300);
PAINT MONO (3850 1300);
DISPLAY INVISIBLE (3850 1300);
FORCEPROP 1 LAST SIZE 1B
J 0
(3925 1250);
DISPLAY 0.893617 (3925 1250);
PAINT GREEN (3925 1250);
DISPLAY INVISIBLE (3925 1250);
FORCEADD RES..1
(4350 1725);
FORCEPROP 1 LAST TOLERANCE 1%
J 0
(4350 1625);
DISPLAY 0.617021 (4350 1625);
PAINT SKYBLUE (4350 1625);
FORCEPROP 1 LASTPIN (4450 1725) $PN 2
J 0
(4412 1737);
DISPLAY 0.617021 (4412 1737);
PAINT ORANGE (4412 1737);
FORCEPROP 1 LAST LOCATION R4G19
J 0
(4300 1775);
DISPLAY 0.617021 (4300 1775);
PAINT AQUA (4300 1775);
FORCEPROP 1 LAST PART_NUMBER G21796-074
J 0
(4300 1825);
DISPLAY 0.617021 (4300 1825);
PAINT BLUE (4300 1825);
FORCEPROP 1 LAST PACK_TYPE 0402
J 0
(4600 1575);
DISPLAY 0.617021 (4600 1575);
PAINT SKYBLUE (4600 1575);
FORCEPROP 1 LASTPIN (4250 1725) $PN 1
J 0
(4262 1737);
DISPLAY 0.617021 (4262 1737);
PAINT ORANGE (4262 1737);
FORCEPROP 1 LAST VALUE 33.2
J 2
(4325 1625);
DISPLAY 0.617021 (4325 1625);
PAINT SKYBLUE (4325 1625);
FORCEPROP 1 LAST MATERIAL CHIP
J 0
(4350 1575);
DISPLAY 0.617021 (4350 1575);
PAINT SKYBLUE (4350 1575);
FORCEPROP 1 LAST WATTAGE 1/16W
J 2
(4325 1575);
DISPLAY 0.617021 (4325 1575);
PAINT SKYBLUE (4325 1575);
FORCEPROP 1 LAST PATH I33
J 0
(4300 1875);
DISPLAY 0.978723 (4300 1875);
PAINT WHITE (4300 1875);
DISPLAY INVISIBLE (4300 1875);
FORCEPROP 0 LAST CDS_SEC 1
J 0
(4300 1875);
PAINT MONO (4300 1875);
DISPLAY INVISIBLE (4300 1875);
FORCEPROP 2 LAST SEC 1
J 0
(4300 1925);
DISPLAY 0.680851 (4300 1925);
PAINT MONO (4300 1925);
DISPLAY INVISIBLE (4300 1925);
FORCEPROP 2 LAST CDS_LIB mstr_discrete
J 0
(4350 1725);
PAINT MONO (4350 1725);
DISPLAY INVISIBLE (4350 1725);
FORCEPROP 2 LAST SEC_TYPE 0402
J 0
(4300 1925);
DISPLAY 1.021277 (4300 1925);
PAINT ORANGE (4300 1925);
DISPLAY INVISIBLE (4300 1925);
FORCEPROP 2 LAST CDS_LOCATION R4G19
J 0
(4300 1775);
DISPLAY 0.617021 (4300 1775);
PAINT AQUA (4300 1775);
DISPLAY INVISIBLE (4300 1775);
FORCEADD PVTT_ABC..1
(5250 1500);
FORCEPROP 3 LASTPIN (5250 1450) SIG_NAME PVTT_ABC\g
J 0
(5260 1460);
DISPLAY 0.659574 (5260 1460);
PAINT MONO (5260 1460);
DISPLAY INVISIBLE (5260 1460);
FORCEPROP 1 LAST HDL_POWER PVTT_ABC
J 1
(5250 1550);
DISPLAY 0.872340 (5250 1550);
PAINT GREEN (5250 1550);
DISPLAY INVISIBLE (5250 1550);
FORCEPROP 1 LAST BODY_TYPE PLUMBING
J 0
(5205 1457);
DISPLAY 0.340426 (5205 1457);
PAINT GREEN (5205 1457);
DISPLAY INVISIBLE (5205 1457);
FORCEPROP 1 LAST PATH I34
J 0
(5300 1525);
DISPLAY 0.872340 (5300 1525);
PAINT AQUA (5300 1525);
DISPLAY INVISIBLE (5300 1525);
FORCEPROP 2 LAST CDS_LIB mstr_symbols
J 0
(5250 1500);
PAINT ORANGE (5250 1500);
DISPLAY INVISIBLE (5250 1500);
FORCEPROP 1 LAST VOLTAGE 0.6V
J 0
(5205 1457);
DISPLAY 0.340426 (5205 1457);
PAINT SKYBLUE (5205 1457);
DISPLAY INVISIBLE (5205 1457);
FORCEADD OFFPAGE..2
(5100 1725);
FORCEPROP 2 LAST $XR0 222 
J 0
(5289 1725);
DISPLAY 0.638298 (5289 1725);
PAINT MONO (5289 1725);
FORCEPROP 2 LAST $XR1 191 
J 0
(5409 1725);
DISPLAY 0.638298 (5409 1725);
PAINT MONO (5409 1725);
FORCEPROP 1 LAST COMMENT_BODY TRUE
J 0
(5055 1630);
DISPLAY 0.872340 (5055 1630);
PAINT GREEN (5055 1630);
DISPLAY INVISIBLE (5055 1630);
FORCEPROP 1 LAST OFFPAGE TRUE
J 0
(5425 1600);
DISPLAY 0.872340 (5425 1600);
PAINT GREEN (5425 1600);
DISPLAY INVISIBLE (5425 1600);
FORCEPROP 2 LAST PATH I35
J 0
(5425 1775);
DISPLAY 1.021277 (5425 1775);
PAINT ORANGE (5425 1775);
DISPLAY INVISIBLE (5425 1775);
FORCEPROP 2 LAST CDS_LIB mstr_standard
J 0
(5100 1725);
DISPLAY 0.744681 (5100 1725);
PAINT MONO (5100 1725);
DISPLAY INVISIBLE (5100 1725);
FORCEADD GND..1
(3325 2825);
FORCEPROP 3 LASTPIN (3325 2875) SIG_NAME GND\g
J 0
(3335 2885);
DISPLAY 0.659574 (3335 2885);
PAINT MONO (3335 2885);
DISPLAY INVISIBLE (3335 2885);
FORCEPROP 1 LAST HDL_POWER GND
J 0
(3325 2975);
DISPLAY 0.893617 (3325 2975);
PAINT GREEN (3325 2975);
DISPLAY INVISIBLE (3325 2975);
FORCEPROP 1 LAST BODY_TYPE PLUMBING
J 0
(3280 2782);
DISPLAY 0.340426 (3280 2782);
PAINT GREEN (3280 2782);
DISPLAY INVISIBLE (3280 2782);
FORCEPROP 1 LAST PATH I36
J 0
(3400 2825);
DISPLAY 0.872340 (3400 2825);
PAINT AQUA (3400 2825);
DISPLAY INVISIBLE (3400 2825);
FORCEPROP 2 LAST CDS_LIB mstr_symbols
J 0
(3325 2825);
PAINT ORANGE (3325 2825);
DISPLAY INVISIBLE (3325 2825);
FORCEPROP 1 LAST VOLTAGE 0.0V
J 0
(3280 2782);
DISPLAY 0.340426 (3280 2782);
PAINT SKYBLUE (3280 2782);
DISPLAY INVISIBLE (3280 2782);
FORCEPROP 1 LAST SIZE 1B
J 0
(3400 2775);
DISPLAY 0.893617 (3400 2775);
PAINT GREEN (3400 2775);
DISPLAY INVISIBLE (3400 2775);
FORCEPROP 2 LAST BOM_COST MEM_VRD_PVDDQ_AB
J 0
(3000 2900);
PAINT MONO (3000 2900);
DISPLAY INVISIBLE (3000 2900);
FORCEPROP 2 LAST ROOM VTT_ABC_PWR_VR
J 0
(2775 2900);
PAINT ORANGE (2775 2900);
DISPLAY INVISIBLE (2775 2900);
FORCEADD RES..1
(-800 50);
FORCEPROP 1 LAST PART_NUMBER G21497-005
J 0
(-975 0);
DISPLAY 0.617021 (-975 0);
PAINT BLUE (-975 0);
FORCEPROP 1 LAST PACK_TYPE 0402
J 0
(-875 -125);
DISPLAY 0.617021 (-875 -125);
PAINT SKYBLUE (-875 -125);
FORCEPROP 1 LAST VALUE 0.0
J 2
(-825 -50);
DISPLAY 0.617021 (-825 -50);
PAINT SKYBLUE (-825 -50);
FORCEPROP 1 LAST TOLERANCE 5%
J 0
(-800 -50);
DISPLAY 0.617021 (-800 -50);
PAINT SKYBLUE (-800 -50);
FORCEPROP 1 LAST MATERIAL CHIP
J 0
(-1100 -125);
DISPLAY 0.617021 (-1100 -125);
PAINT SKYBLUE (-1100 -125);
FORCEPROP 1 LAST WATTAGE 1/16W
J 2
(-950 -50);
DISPLAY 0.617021 (-950 -50);
PAINT SKYBLUE (-950 -50);
FORCEPROP 1 LAST LOCATION R4G23
J 0
(-850 100);
DISPLAY 0.617021 (-850 100);
PAINT AQUA (-850 100);
FORCEPROP 1 LASTPIN (-700 50) $PN 2
J 0
(-738 62);
DISPLAY 0.617021 (-738 62);
PAINT WHITE (-738 62);
FORCEPROP 1 LASTPIN (-900 50) $PN 1
J 0
(-888 62);
DISPLAY 0.617021 (-888 62);
PAINT WHITE (-888 62);
FORCEPROP 1 LAST PATH I4
J 0
(-850 200);
DISPLAY 0.978723 (-850 200);
PAINT WHITE (-850 200);
DISPLAY INVISIBLE (-850 200);
FORCEPROP 0 LAST CDS_SEC 1
J 0
(-850 150);
PAINT MONO (-850 150);
DISPLAY INVISIBLE (-850 150);
FORCEPROP 2 LAST BOM_COST MEM_VRD_VTT_ABC
J 0
(-830 255);
DISPLAY 1.021277 (-830 255);
PAINT ORANGE (-830 255);
DISPLAY INVISIBLE (-830 255);
FORCEPROP 2 LAST SEC_TYPE 0402
J 0
(-850 250);
DISPLAY 1.021277 (-850 250);
PAINT ORANGE (-850 250);
DISPLAY INVISIBLE (-850 250);
FORCEPROP 2 LAST SEC 1
J 0
(-850 250);
DISPLAY 0.680851 (-850 250);
PAINT MONO (-850 250);
DISPLAY INVISIBLE (-850 250);
FORCEPROP 2 LAST ROOM VTT_ABC_PWR_VR
J 0
(-830 205);
DISPLAY 1.021277 (-830 205);
PAINT ORANGE (-830 205);
DISPLAY INVISIBLE (-830 205);
FORCEPROP 2 LAST CDS_LIB mstr_discrete
J 0
(-800 50);
PAINT ORANGE (-800 50);
DISPLAY INVISIBLE (-800 50);
FORCEPROP 2 LAST CDS_LOCATION R4G23
J 0
(-850 100);
DISPLAY 0.617021 (-850 100);
PAINT AQUA (-850 100);
DISPLAY INVISIBLE (-850 100);
FORCEADD CAP_A..1
(4075 3300);
FORCEPROP 1 LAST PACK_TYPE 0603V
J 0
(4125 3100);
DISPLAY 0.617021 (4125 3100);
PAINT SKYBLUE (4125 3100);
FORCEPROP 1 LASTPIN (4075 3400) $PN 1
J 0
(4085 3380);
DISPLAY 0.617021 (4085 3380);
PAINT ORANGE (4085 3380);
FORCEPROP 1 LAST VOLTAGE 4V
J 0
(4125 3300);
DISPLAY 0.617021 (4125 3300);
PAINT SKYBLUE (4125 3300);
FORCEPROP 1 LAST TOLERANCE 20%
J 0
(4125 3250);
DISPLAY 0.617021 (4125 3250);
PAINT SKYBLUE (4125 3250);
FORCEPROP 1 LASTPIN (4075 3200) $PN 2
J 0
(4085 3180);
DISPLAY 0.617021 (4085 3180);
PAINT ORANGE (4085 3180);
FORCEPROP 1 LAST MATERIAL X5R
J 0
(4125 3200);
DISPLAY 0.617021 (4125 3200);
PAINT SKYBLUE (4125 3200);
FORCEPROP 1 LAST PART_NUMBER 602433-106
J 0
(4125 3150);
DISPLAY 0.617021 (4125 3150);
PAINT BLUE (4125 3150);
FORCEPROP 1 LAST VALUE 47UF
J 0
(4125 3350);
DISPLAY 0.617021 (4125 3350);
PAINT SKYBLUE (4125 3350);
FORCEPROP 1 LAST LOCATION C5T3
J 0
(4125 3400);
DISPLAY 0.617021 (4125 3400);
PAINT AQUA (4125 3400);
FORCEPROP 0 LAST GROUP PWR_MLCC_CAP
J 0
(4131 3037);
DISPLAY 0.638298 (4131 3037);
PAINT BROWN (4131 3037);
DISPLAY BOTH (4131 3037);
FORCEPROP 1 LAST PATH I40
J 0
(4125 3450);
DISPLAY 0.978723 (4125 3450);
PAINT WHITE (4125 3450);
DISPLAY INVISIBLE (4125 3450);
FORCEPROP 2 LAST CDS_SEC 1
J 0
(4125 3450);
PAINT ORANGE (4125 3450);
DISPLAY INVISIBLE (4125 3450);
FORCEPROP 2 LAST SEC_TYPE 0603V
J 0
(4125 3500);
DISPLAY 1.021277 (4125 3500);
PAINT ORANGE (4125 3500);
DISPLAY INVISIBLE (4125 3500);
FORCEPROP 2 LAST SEC 1
J 0
(4125 3500);
DISPLAY 0.680851 (4125 3500);
PAINT MONO (4125 3500);
DISPLAY INVISIBLE (4125 3500);
FORCEPROP 2 LAST CDS_LOCATION C5T3
J 0
(4125 3400);
DISPLAY 0.617021 (4125 3400);
PAINT AQUA (4125 3400);
DISPLAY INVISIBLE (4125 3400);
FORCEPROP 2 LAST CDS_LIB dev_discrete
J 0
(4075 3300);
PAINT ORANGE (4075 3300);
DISPLAY INVISIBLE (4075 3300);
FORCEADD CAP..1
(4425 975);
FORCEPROP 1 LAST PART_NUMBER 602433-112
J 0
(4475 875);
DISPLAY 0.617021 (4475 875);
PAINT BLUE (4475 875);
FORCEPROP 0 LAST GROUP PWR_MLCC_CAP
J 0
(4481 687);
DISPLAY 0.638298 (4481 687);
PAINT BROWN (4481 687);
DISPLAY BOTH (4481 687);
FORCEPROP 1 LAST LOCATION C6W11
J 0
(4475 1075);
DISPLAY 0.617021 (4475 1075);
PAINT AQUA (4475 1075);
FORCEPROP 1 LAST VALUE 100UF
J 0
(4475 1025);
DISPLAY 0.617021 (4475 1025);
PAINT SKYBLUE (4475 1025);
FORCEPROP 0 LAST NEW_MATERIAL X6S
J 0
(4475 725);
DISPLAY 0.638298 (4475 725);
PAINT BROWN (4475 725);
DISPLAY BOTH (4475 725);
FORCEPROP 1 LASTPIN (4425 1075) $PN 1
J 0
(4435 1055);
DISPLAY 0.617021 (4435 1055);
PAINT ORANGE (4435 1055);
FORCEPROP 1 LASTPIN (4425 875) $PN 2
J 0
(4435 855);
DISPLAY 0.617021 (4435 855);
PAINT ORANGE (4435 855);
FORCEPROP 1 LAST TOLERANCE 20%
J 0
(4475 925);
DISPLAY 0.617021 (4475 925);
PAINT SKYBLUE (4475 925);
FORCEPROP 1 LAST VOLTAGE 4V
J 0
(4475 975);
DISPLAY 0.617021 (4475 975);
PAINT SKYBLUE (4475 975);
FORCEPROP 1 LAST PACK_TYPE 0805
J 0
(4475 825);
DISPLAY 0.617021 (4475 825);
PAINT SKYBLUE (4475 825);
FORCEPROP 0 LAST NEW_PN 078.1071T.M002
J 0
(4481 770);
DISPLAY 0.638298 (4481 770);
PAINT BROWN (4481 770);
DISPLAY BOTH (4481 770);
FORCEPROP 2 LAST CDS_LOCATION C6W11
J 0
(4475 1075);
DISPLAY 0.617021 (4475 1075);
PAINT AQUA (4475 1075);
DISPLAY INVISIBLE (4475 1075);
FORCEPROP 0 LAST CDS_SEC 1
J 0
(4475 1125);
PAINT MONO (4475 1125);
DISPLAY INVISIBLE (4475 1125);
FORCEPROP 2 LAST CDS_LIB mstr_discrete
J 0
(4425 975);
PAINT MONO (4425 975);
DISPLAY INVISIBLE (4425 975);
FORCEPROP 2 LAST BOM_COST MEM_VRD_PVDDQ_CD
J 0
(4475 1125);
PAINT MONO (4475 1125);
DISPLAY INVISIBLE (4475 1125);
FORCEPROP 2 LAST ROOM VDDQ_ABC_PWR_VR
J 0
(4475 1125);
PAINT MONO (4475 1125);
DISPLAY INVISIBLE (4475 1125);
FORCEPROP 2 LAST SEC_TYPE 0805
J 0
(4475 1175);
DISPLAY 1.021277 (4475 1175);
PAINT ORANGE (4475 1175);
DISPLAY INVISIBLE (4475 1175);
FORCEPROP 2 LAST SEC 1
J 0
(4475 1175);
DISPLAY 0.680851 (4475 1175);
PAINT MONO (4475 1175);
DISPLAY INVISIBLE (4475 1175);
FORCEPROP 1 LAST MATERIAL X5R
J 0
(4475 875);
DISPLAY 0.617021 (4475 875);
PAINT SKYBLUE (4475 875);
DISPLAY INVISIBLE (4475 875);
FORCEPROP 1 LAST PATH I44
J 0
(4475 1125);
DISPLAY 0.978723 (4475 1125);
PAINT WHITE (4475 1125);
DISPLAY INVISIBLE (4475 1125);
FORCEADD CAP..1
(3325 3300);
FORCEPROP 0 LAST GROUP PWR_MLCC_CAP
J 0
(3381 3012);
DISPLAY 0.638298 (3381 3012);
PAINT BROWN (3381 3012);
DISPLAY BOTH (3381 3012);
FORCEPROP 0 LAST NEW_PN 078.1071T.M002
J 0
(3386 3090);
DISPLAY 0.638298 (3386 3090);
PAINT BROWN (3386 3090);
DISPLAY BOTH (3386 3090);
FORCEPROP 1 LAST PACK_TYPE 0805
J 0
(3375 3150);
DISPLAY 0.617021 (3375 3150);
PAINT SKYBLUE (3375 3150);
FORCEPROP 0 LAST NEW_MATERIAL X6S
J 0
(3375 3050);
DISPLAY 0.638298 (3375 3050);
PAINT BROWN (3375 3050);
DISPLAY BOTH (3375 3050);
FORCEPROP 1 LASTPIN (3325 3400) $PN 1
J 0
(3335 3380);
DISPLAY 0.617021 (3335 3380);
PAINT ORANGE (3335 3380);
FORCEPROP 1 LASTPIN (3325 3200) $PN 2
J 0
(3335 3180);
DISPLAY 0.617021 (3335 3180);
PAINT ORANGE (3335 3180);
FORCEPROP 1 LAST TOLERANCE 20%
J 0
(3375 3250);
DISPLAY 0.617021 (3375 3250);
PAINT SKYBLUE (3375 3250);
FORCEPROP 1 LAST VOLTAGE 4V
J 0
(3375 3300);
DISPLAY 0.617021 (3375 3300);
PAINT SKYBLUE (3375 3300);
FORCEPROP 1 LAST VALUE 100UF
J 0
(3375 3350);
DISPLAY 0.617021 (3375 3350);
PAINT SKYBLUE (3375 3350);
FORCEPROP 1 LAST PART_NUMBER 602433-112
J 0
(3375 3200);
DISPLAY 0.617021 (3375 3200);
PAINT BLUE (3375 3200);
FORCEPROP 1 LAST LOCATION C5U12
J 0
(3375 3400);
DISPLAY 0.617021 (3375 3400);
PAINT AQUA (3375 3400);
FORCEPROP 2 LAST CDS_LOCATION C5U12
J 0
(3375 3400);
DISPLAY 0.617021 (3375 3400);
PAINT AQUA (3375 3400);
DISPLAY INVISIBLE (3375 3400);
FORCEPROP 0 LAST CDS_SEC 1
J 0
(3375 3450);
PAINT MONO (3375 3450);
DISPLAY INVISIBLE (3375 3450);
FORCEPROP 2 LAST CDS_LIB mstr_discrete
J 0
(3325 3300);
PAINT MONO (3325 3300);
DISPLAY INVISIBLE (3325 3300);
FORCEPROP 2 LAST BOM_COST MEM_VRD_PVDDQ_CD
J 0
(3375 3450);
PAINT MONO (3375 3450);
DISPLAY INVISIBLE (3375 3450);
FORCEPROP 2 LAST ROOM VDDQ_ABC_PWR_VR
J 0
(3375 3450);
PAINT MONO (3375 3450);
DISPLAY INVISIBLE (3375 3450);
FORCEPROP 2 LAST SEC_TYPE 0805
J 0
(3375 3500);
DISPLAY 1.021277 (3375 3500);
PAINT ORANGE (3375 3500);
DISPLAY INVISIBLE (3375 3500);
FORCEPROP 2 LAST SEC 1
J 0
(3375 3500);
DISPLAY 0.680851 (3375 3500);
PAINT MONO (3375 3500);
DISPLAY INVISIBLE (3375 3500);
FORCEPROP 1 LAST MATERIAL X5R
J 0
(3375 3200);
DISPLAY 0.617021 (3375 3200);
PAINT SKYBLUE (3375 3200);
DISPLAY INVISIBLE (3375 3200);
FORCEPROP 1 LAST PATH I45
J 0
(3375 3450);
DISPLAY 0.978723 (3375 3450);
PAINT WHITE (3375 3450);
DISPLAY INVISIBLE (3375 3450);
FORCEADD CAP..1
(3675 3300);
FORCEPROP 0 LAST NEW_MATERIAL X6S
J 0
(3725 2900);
DISPLAY 0.638298 (3725 2900);
PAINT BROWN (3725 2900);
DISPLAY BOTH (3725 2900);
FORCEPROP 1 LAST VALUE 100UF
J 0
(3725 3350);
DISPLAY 0.617021 (3725 3350);
PAINT SKYBLUE (3725 3350);
FORCEPROP 1 LAST PACK_TYPE 0805
J 0
(3725 3150);
DISPLAY 0.617021 (3725 3150);
PAINT SKYBLUE (3725 3150);
FORCEPROP 1 LAST PART_NUMBER 602433-112
J 0
(3725 3200);
DISPLAY 0.617021 (3725 3200);
PAINT BLUE (3725 3200);
FORCEPROP 1 LAST LOCATION C5U16
J 0
(3725 3400);
DISPLAY 0.617021 (3725 3400);
PAINT AQUA (3725 3400);
FORCEPROP 1 LASTPIN (3675 3400) $PN 1
J 0
(3685 3380);
DISPLAY 0.617021 (3685 3380);
PAINT ORANGE (3685 3380);
FORCEPROP 1 LASTPIN (3675 3200) $PN 2
J 0
(3685 3180);
DISPLAY 0.617021 (3685 3180);
PAINT ORANGE (3685 3180);
FORCEPROP 1 LAST TOLERANCE 20%
J 0
(3725 3250);
DISPLAY 0.617021 (3725 3250);
PAINT SKYBLUE (3725 3250);
FORCEPROP 1 LAST VOLTAGE 4V
J 0
(3725 3300);
DISPLAY 0.617021 (3725 3300);
PAINT SKYBLUE (3725 3300);
FORCEPROP 0 LAST GROUP PWR_MLCC_CAP
J 0
(3731 2862);
DISPLAY 0.638298 (3731 2862);
PAINT BROWN (3731 2862);
DISPLAY BOTH (3731 2862);
FORCEPROP 0 LAST NEW_PN 078.1071T.M002
J 0
(3731 2945);
DISPLAY 0.638298 (3731 2945);
PAINT BROWN (3731 2945);
DISPLAY BOTH (3731 2945);
FORCEPROP 2 LAST CDS_LOCATION C5U16
J 0
(3725 3400);
DISPLAY 0.617021 (3725 3400);
PAINT AQUA (3725 3400);
DISPLAY INVISIBLE (3725 3400);
FORCEPROP 1 LAST PATH I46
J 0
(3725 3450);
DISPLAY 0.978723 (3725 3450);
PAINT WHITE (3725 3450);
DISPLAY INVISIBLE (3725 3450);
FORCEPROP 0 LAST CDS_SEC 1
J 0
(3725 3450);
PAINT MONO (3725 3450);
DISPLAY INVISIBLE (3725 3450);
FORCEPROP 2 LAST CDS_LIB mstr_discrete
J 0
(3675 3300);
PAINT MONO (3675 3300);
DISPLAY INVISIBLE (3675 3300);
FORCEPROP 2 LAST BOM_COST MEM_VRD_PVDDQ_CD
J 0
(3725 3450);
PAINT MONO (3725 3450);
DISPLAY INVISIBLE (3725 3450);
FORCEPROP 2 LAST ROOM VDDQ_ABC_PWR_VR
J 0
(3725 3450);
PAINT MONO (3725 3450);
DISPLAY INVISIBLE (3725 3450);
FORCEPROP 2 LAST SEC_TYPE 0805
J 0
(3725 3500);
DISPLAY 1.021277 (3725 3500);
PAINT ORANGE (3725 3500);
DISPLAY INVISIBLE (3725 3500);
FORCEPROP 2 LAST SEC 1
J 0
(3725 3500);
DISPLAY 0.680851 (3725 3500);
PAINT MONO (3725 3500);
DISPLAY INVISIBLE (3725 3500);
FORCEPROP 1 LAST MATERIAL X5R
J 0
(3725 3200);
DISPLAY 0.617021 (3725 3200);
PAINT SKYBLUE (3725 3200);
DISPLAY INVISIBLE (3725 3200);
FORCEADD RES..2
R 2
(-600 575);
FORCEPROP 1 LAST PACK_TYPE 0402
J 2
(-640 400);
DISPLAY 0.617021 (-640 400);
PAINT SKYBLUE (-640 400);
FORCEPROP 1 LAST PART_NUMBER G21796-021
J 2
(-640 450);
DISPLAY 0.617021 (-640 450);
PAINT BLUE (-640 450);
FORCEPROP 1 LAST MATERIAL EMPTY
J 2
(-640 500);
DISPLAY 0.617021 (-640 500);
PAINT RED (-640 500);
FORCEPROP 1 LAST WATTAGE 1/16W
J 2
(-640 550);
DISPLAY 0.617021 (-640 550);
PAINT SKYBLUE (-640 550);
FORCEPROP 1 LAST TOLERANCE 1%
J 2
(-645 600);
DISPLAY 0.617021 (-645 600);
PAINT SKYBLUE (-645 600);
FORCEPROP 1 LAST VALUE 1.0M
J 2
(-645 650);
DISPLAY 0.617021 (-645 650);
PAINT SKYBLUE (-645 650);
FORCEPROP 1 LAST LOCATION R6U15
J 2
(-645 700);
DISPLAY 0.617021 (-645 700);
PAINT AQUA (-645 700);
FORCEPROP 1 LASTPIN (-600 675) $PN 1
J 2
(-605 637);
DISPLAY 0.617021 (-605 637);
PAINT WHITE (-605 637);
FORCEPROP 1 LASTPIN (-600 475) $PN 2
J 2
(-605 485);
DISPLAY 0.617021 (-605 485);
PAINT WHITE (-605 485);
FORCEPROP 1 LAST PATH I5
J 2
(-650 750);
DISPLAY 0.978723 (-650 750);
PAINT WHITE (-650 750);
DISPLAY INVISIBLE (-650 750);
FORCEPROP 0 LAST CDS_SEC 1
J 0
(-625 750);
PAINT MONO (-625 750);
DISPLAY INVISIBLE (-625 750);
FORCEPROP 2 LAST ROOM VTT_ABC_PWR_VR
J 0
(-635 740);
DISPLAY 1.021277 (-635 740);
PAINT ORANGE (-635 740);
DISPLAY INVISIBLE (-635 740);
FORCEPROP 2 LAST CDS_LOCATION R6U15
J 2
(-645 700);
DISPLAY 0.617021 (-645 700);
PAINT AQUA (-645 700);
DISPLAY INVISIBLE (-645 700);
FORCEPROP 2 LAST SEC 1
J 0
(-629 805);
DISPLAY 0.680851 (-629 805);
PAINT MONO (-629 805);
DISPLAY INVISIBLE (-629 805);
FORCEPROP 2 LAST BOM_COST MEM_VRD_VTT_ABC
J 0
(-635 790);
DISPLAY 1.021277 (-635 790);
PAINT ORANGE (-635 790);
DISPLAY INVISIBLE (-635 790);
FORCEPROP 2 LAST SEC_TYPE 0402
J 0
(-629 805);
DISPLAY 1.021277 (-629 805);
PAINT ORANGE (-629 805);
DISPLAY INVISIBLE (-629 805);
FORCEPROP 2 LAST CDS_LIB mstr_discrete
J 0
(-600 575);
PAINT ORANGE (-600 575);
DISPLAY INVISIBLE (-600 575);
FORCEADD RES..2
R 1
(-1050 1450);
FORCEPROP 1 LAST PART_NUMBER G21497-005
J 0
(-1150 1340);
DISPLAY 0.617021 (-1150 1340);
PAINT BLUE (-1150 1340);
FORCEPROP 1 LAST WATTAGE 1/16W
J 0
(-1025 1390);
DISPLAY 0.617021 (-1025 1390);
PAINT SKYBLUE (-1025 1390);
FORCEPROP 1 LAST VALUE 0.0
J 0
(-1125 1395);
DISPLAY 0.617021 (-1125 1395);
PAINT SKYBLUE (-1125 1395);
FORCEPROP 1 LAST TOLERANCE 5%
J 0
(-1200 1395);
DISPLAY 0.617021 (-1200 1395);
PAINT SKYBLUE (-1200 1395);
FORCEPROP 1 LASTPIN (-1150 1450) $PN 1
R 1
J 0
(-1112 1455);
DISPLAY 0.617021 (-1112 1455);
PAINT WHITE (-1112 1455);
FORCEPROP 1 LAST LOCATION R6U5
J 0
(-1075 1495);
DISPLAY 0.617021 (-1075 1495);
PAINT AQUA (-1075 1495);
FORCEPROP 1 LAST PACK_TYPE 0402
J 0
(-900 1390);
DISPLAY 0.617021 (-900 1390);
PAINT SKYBLUE (-900 1390);
FORCEPROP 1 LASTPIN (-950 1450) $PN 2
R 1
J 0
(-960 1455);
DISPLAY 0.617021 (-960 1455);
PAINT WHITE (-960 1455);
FORCEPROP 1 LAST PATH I6
R 1
J 0
(-1225 1500);
DISPLAY 0.978723 (-1225 1500);
PAINT WHITE (-1225 1500);
DISPLAY INVISIBLE (-1225 1500);
FORCEPROP 0 LAST CDS_SEC 1
R 1
J 0
(-1075 1525);
PAINT MONO (-1075 1525);
DISPLAY INVISIBLE (-1075 1525);
FORCEPROP 2 LAST SEC_TYPE 0402
J 0
(-1069 1540);
DISPLAY 1.021277 (-1069 1540);
PAINT ORANGE (-1069 1540);
DISPLAY INVISIBLE (-1069 1540);
FORCEPROP 2 LAST BOM_COST MEM_VRD_VTT_ABC
J 0
(-1075 1600);
DISPLAY 1.021277 (-1075 1600);
PAINT ORANGE (-1075 1600);
DISPLAY INVISIBLE (-1075 1600);
FORCEPROP 2 LAST SEC 1
J 0
(-1069 1540);
DISPLAY 0.680851 (-1069 1540);
PAINT MONO (-1069 1540);
DISPLAY INVISIBLE (-1069 1540);
FORCEPROP 2 LAST CDS_LOCATION R6U5
J 0
(-1075 1495);
DISPLAY 0.617021 (-1075 1495);
PAINT AQUA (-1075 1495);
DISPLAY INVISIBLE (-1075 1495);
FORCEPROP 0 LAST NO_XNET_CONNECTION 1
J 0
(-1075 1525);
PAINT MONO (-1075 1525);
DISPLAY INVISIBLE (-1075 1525);
FORCEPROP 2 LAST ROOM VTT_ABC_PWR_VR
J 0
(-1075 1550);
DISPLAY 1.021277 (-1075 1550);
PAINT ORANGE (-1075 1550);
DISPLAY INVISIBLE (-1075 1550);
FORCEPROP 1 LAST MATERIAL CHIP
J 0
(-1125 1215);
PAINT SKYBLUE (-1125 1215);
DISPLAY INVISIBLE (-1125 1215);
FORCEPROP 2 LAST CDS_LIB mstr_discrete
R 1
J 0
(-1050 1450);
PAINT ORANGE (-1050 1450);
DISPLAY INVISIBLE (-1050 1450);
FORCEADD P3V3..1
(-825 1975);
FORCEPROP 3 LASTPIN (-825 1925) SIG_NAME P3V3\g
J 0
(-815 1935);
DISPLAY 0.659574 (-815 1935);
PAINT MONO (-815 1935);
DISPLAY INVISIBLE (-815 1935);
FORCEPROP 1 LAST HDL_POWER P3V3
J 0
(-1150 1850);
DISPLAY 0.872340 (-1150 1850);
PAINT ORANGE (-1150 1850);
DISPLAY INVISIBLE (-1150 1850);
FORCEPROP 1 LAST BODY_TYPE PLUMBING
J 0
(-870 1932);
DISPLAY 0.340426 (-870 1932);
PAINT GREEN (-870 1932);
DISPLAY INVISIBLE (-870 1932);
FORCEPROP 1 LAST PATH I7
J 0
(-780 1977);
DISPLAY 0.340426 (-780 1977);
PAINT GREEN (-780 1977);
DISPLAY INVISIBLE (-780 1977);
FORCEPROP 2 LAST CDS_LIB mstr_symbols
J 0
(-825 1975);
PAINT ORANGE (-825 1975);
DISPLAY INVISIBLE (-825 1975);
FORCEPROP 1 LAST SIZE 1B
J 0
(-780 1997);
DISPLAY 0.340426 (-780 1997);
PAINT GREEN (-780 1997);
DISPLAY INVISIBLE (-780 1997);
FORCEPROP 1 LAST VOLTAGE 3.3V
J 0
(-870 1932);
DISPLAY 0.340426 (-870 1932);
PAINT SKYBLUE (-870 1932);
DISPLAY INVISIBLE (-870 1932);
FORCEADD PVDDQ_ABC..1
(-1700 2700);
FORCEPROP 3 LASTPIN (-1700 2650) SIG_NAME PVDDQ_ABC\g
J 0
(-1690 2660);
DISPLAY 0.659574 (-1690 2660);
PAINT MONO (-1690 2660);
DISPLAY INVISIBLE (-1690 2660);
FORCEPROP 1 LAST HDL_POWER PVDDQ_ABC
J 1
(-1700 2750);
DISPLAY 0.872340 (-1700 2750);
PAINT GREEN (-1700 2750);
DISPLAY INVISIBLE (-1700 2750);
FORCEPROP 1 LAST BODY_TYPE PLUMBING
J 0
(-1745 2657);
DISPLAY 0.340426 (-1745 2657);
PAINT GREEN (-1745 2657);
DISPLAY INVISIBLE (-1745 2657);
FORCEPROP 1 LAST PATH I8
J 0
(-1650 2725);
DISPLAY 0.872340 (-1650 2725);
PAINT AQUA (-1650 2725);
DISPLAY INVISIBLE (-1650 2725);
FORCEPROP 2 LAST CDS_LIB mstr_symbols
J 0
(-1700 2700);
PAINT ORANGE (-1700 2700);
DISPLAY INVISIBLE (-1700 2700);
FORCEPROP 1 LAST VOLTAGE 1.2V
J 0
(-1745 2657);
DISPLAY 0.340426 (-1745 2657);
PAINT SKYBLUE (-1745 2657);
DISPLAY INVISIBLE (-1745 2657);
FORCEADD SHUNT..1
(4700 -75);
FORCEPROP 1 LASTPIN (4850 -75) $PN 2
J 0
(4810 -65);
DISPLAY 0.617021 (4810 -65);
PAINT ORANGE (4810 -65);
FORCEPROP 1 LAST LOCATION SH5U1
J 0
(4625 -25);
DISPLAY 0.617021 (4625 -25);
PAINT AQUA (4625 -25);
FORCEPROP 1 LASTPIN (4550 -75) $PN 1
J 2
(4600 -65);
DISPLAY 0.617021 (4600 -65);
PAINT ORANGE (4600 -65);
FORCEPROP 1 LAST PART_NUMBER N_A
J 0
(4625 -165);
DISPLAY 0.617021 (4625 -165);
PAINT BLUE (4625 -165);
FORCEPROP 1 LAST PATH I9
J 0
(4650 25);
DISPLAY 0.978723 (4650 25);
PAINT ORANGE (4650 25);
DISPLAY INVISIBLE (4650 25);
FORCEPROP 0 LAST CDS_SEC 1
J 0
(4625 25);
PAINT MONO (4625 25);
DISPLAY INVISIBLE (4625 25);
FORCEPROP 0 LAST CDS_LOCATION SH5U1
J 0
(4625 25);
PAINT MONO (4625 25);
DISPLAY INVISIBLE (4625 25);
FORCEPROP 2 LAST SEC_TYPE SH0201
J 0
(4650 75);
DISPLAY 1.021277 (4650 75);
PAINT ORANGE (4650 75);
DISPLAY INVISIBLE (4650 75);
FORCEPROP 0 LAST SEC 1
J 0
(4625 25);
DISPLAY 0.680851 (4625 25);
PAINT MONO (4625 25);
DISPLAY INVISIBLE (4625 25);
FORCEPROP 2 LAST CDS_LIB mstr_misc
J 0
(4700 -75);
PAINT ORANGE (4700 -75);
DISPLAY INVISIBLE (4700 -75);
FORCEPROP 1 LAST MATERIAL EMPTY
J 0
(4625 -210);
DISPLAY 0.978723 (4625 -210);
PAINT RED (4625 -210);
DISPLAY INVISIBLE (4625 -210);
FORCEPROP 1 LAST PACK_TYPE SH0201
J 0
(4640 -260);
DISPLAY 0.978723 (4640 -260);
PAINT SKYBLUE (4640 -260);
DISPLAY INVISIBLE (4640 -260);
FORCEPROP 1 LAST PIN_SHORT A:B
J 0
(4625 -325);
DISPLAY 1.021277 (4625 -325);
PAINT ORANGE (4625 -325);
DISPLAY INVISIBLE (4625 -325);
FORCEADD CAD_NOTE..1
(-175 2675);
FORCEPROP 0 LAST L1 PLACE CLOSE TO CONTROLLER
J 0
(-262 2583);
DISPLAY 0.617021 (-262 2583);
PAINT WHITE (-262 2583);
FORCEPROP 1 LAST COMMENT_BODY TRUE
J 0
(-150 2775);
DISPLAY 0.978723 (-150 2775);
PAINT ORANGE (-150 2775);
DISPLAY INVISIBLE (-150 2775);
FORCEPROP 2 LAST CDS_LIB mstr_symbols
J 0
(-175 2675);
PAINT ORANGE (-175 2675);
DISPLAY INVISIBLE (-175 2675);
FORCEADD PRELIM..6
(1285 965);
PAINT GRAY (1285 965);
FORCEPROP 1 LAST COMMENT_BODY TRUE
J 0
(1285 965);
PAINT ORANGE (1285 965);
DISPLAY INVISIBLE (1285 965);
FORCEPROP 2 LAST CDS_LIB mstr_misc
J 0
(1285 965);
PAINT ORANGE (1285 965);
DISPLAY INVISIBLE (1285 965);
FORCEADD DNS..3
(4705 -80);
PAINT RED (4705 -80);
FORCEPROP 1 LAST COMMENT_BODY TRUE
R 1
J 0
(4780 -305);
DISPLAY 0.872340 (4780 -305);
PAINT GREEN (4780 -305);
DISPLAY INVISIBLE (4780 -305);
FORCEPROP 2 LAST CDS_LIB mstr_misc
J 0
(4705 -80);
PAINT ORANGE (4705 -80);
DISPLAY INVISIBLE (4705 -80);
FORCEADD DNS..2
(-595 570);
PAINT RED (-595 570);
FORCEPROP 1 LAST COMMENT_BODY TRUE
R 1
J 0
(-520 345);
DISPLAY 0.872340 (-520 345);
PAINT GREEN (-520 345);
DISPLAY INVISIBLE (-520 345);
FORCEPROP 2 LAST CDS_LIB mstr_misc
J 0
(-595 570);
PAINT ORANGE (-595 570);
DISPLAY INVISIBLE (-595 570);
FORCEADD CAD_NOTE..1
(1975 1500);
FORCEPROP 0 LAST L1 PLACE CLOSE TO CONTROLLER
J 0
(1793 1408);
DISPLAY 0.617021 (1793 1408);
PAINT WHITE (1793 1408);
FORCEPROP 1 LAST COMMENT_BODY TRUE
J 0
(2000 1600);
DISPLAY 0.978723 (2000 1600);
PAINT ORANGE (2000 1600);
DISPLAY INVISIBLE (2000 1600);
FORCEPROP 2 LAST CDS_LIB mstr_symbols
J 0
(1975 1500);
PAINT ORANGE (1975 1500);
DISPLAY INVISIBLE (1975 1500);
FORCEADD CAD_NOTE..1
(4725 175);
FORCEPROP 0 LAST L1 SPOF
J 0
(4686 76);
DISPLAY 0.617021 (4686 76);
PAINT WHITE (4686 76);
FORCEPROP 1 LAST COMMENT_BODY TRUE
J 0
(4750 275);
DISPLAY 0.978723 (4750 275);
PAINT ORANGE (4750 275);
DISPLAY INVISIBLE (4750 275);
FORCEPROP 2 LAST CDS_LIB mstr_symbols
J 0
(4725 175);
PAINT ORANGE (4725 175);
DISPLAY INVISIBLE (4725 175);
FORCEADD CAD_NOTE..1
(4450 -350);
FORCEPROP 0 LAST L1 PLACE NEAR CENTER
J 0
(4332 -445);
DISPLAY 0.617021 (4332 -445);
PAINT WHITE (4332 -445);
FORCEPROP 0 LAST L2 OF PVTT PLANE
J 0
(4332 -497);
DISPLAY 0.617021 (4332 -497);
PAINT WHITE (4332 -497);
FORCEPROP 1 LAST COMMENT_BODY TRUE
J 0
(4475 -250);
DISPLAY 0.978723 (4475 -250);
PAINT ORANGE (4475 -250);
DISPLAY INVISIBLE (4475 -250);
FORCEPROP 2 LAST CDS_LIB mstr_symbols
J 0
(4450 -350);
PAINT ORANGE (4450 -350);
DISPLAY INVISIBLE (4450 -350);
FORCEADD CAD_NOTE..1
(4550 3425);
FORCEPROP 1 LAST COMMENT_BODY TRUE
J 0
(4575 3525);
DISPLAY 0.978723 (4575 3525);
PAINT ORANGE (4575 3525);
DISPLAY INVISIBLE (4575 3525);
FORCEPROP 2 LAST CDS_LIB mstr_symbols
J 0
(4550 3425);
PAINT ORANGE (4550 3425);
DISPLAY INVISIBLE (4550 3425);
FORCEADD INTEL_CORP_BPAGE..1
(5700 -1150);
FORCEPROP 1 LAST CDS_CON_LAST_MODIFIED Fri Jun 16 17:49:19 2017
J 0
(4275 -825);
PAINT GREEN (4275 -825);
DISPLAY INVISIBLE (4275 -825);
FORCEPROP 1 LAST CUSTOM_TXT_CDS <CURRENT_DESIGN_SHEET> OF <TOTAL_DESIGN_SHEETS>
J 0
(5200 -1125);
PAINT ORANGE (5200 -1125);
FORCEPROP 1 LAST CUSTOM_TXT_CDS <CON_LAST_MODIFIED>
J 0
(1700 -1050);
PAINT ORANGE (1700 -1050);
FORCEPROP 2 LAST CUSTOM_TXT_CDS <XR_PAGE_TITLE>
J 0
(-2190 4100);
DISPLAY 0.638298 (-2190 4100);
PAINT PINK (-2190 4100);
DISPLAY INVISIBLE (-2190 4100);
FORCEPROP 1 LAST SCH_TITLE DDR VTT VR CHANNEL ABC
J 0
(-2250 -1100);
DISPLAY 1.212766 (-2250 -1100);
PAINT GREEN (-2250 -1100);
FORCEPROP 2 LAST CDS_XR_PAGE_TITLE CR-221 : @BASEBOARD_FAB2_LIB.BASEBOARD_FAB2(SCH_1):PAGE221
J 0
(-2190 4100);
DISPLAY 0.638298 (-2190 4100);
PAINT PINK (-2190 4100);
DISPLAY INVISIBLE (-2190 4100);
FORCEPROP 1 LAST COMMENT_BODY TRUE
J 0
(5712 -1138);
DISPLAY 0.446809 (5712 -1138);
PAINT GREEN (5712 -1138);
DISPLAY INVISIBLE (5712 -1138);
FORCEPROP 2 LAST CDS_LIB mstr_symbols
J 0
(5700 -1150);
PAINT ORANGE (5700 -1150);
DISPLAY INVISIBLE (5700 -1150);
FORCEPROP 2 LAST PAGE_BORDER TRUE
J 0
(-2190 4100);
DISPLAY 0.659574 (-2190 4100);
PAINT PINK (-2190 4100);
DISPLAY INVISIBLE (-2190 4100);
FORCEADD DNS..2
(-645 -480);
PAINT RED (-645 -480);
FORCEPROP 1 LAST COMMENT_BODY TRUE
R 1
J 0
(-570 -705);
DISPLAY 0.872340 (-570 -705);
PAINT GREEN (-570 -705);
DISPLAY INVISIBLE (-570 -705);
FORCEPROP 2 LAST CDS_LIB mstr_misc
J 0
(-645 -480);
PAINT ORANGE (-645 -480);
DISPLAY INVISIBLE (-645 -480);
WIRE 16 -1 (-650 -650)(-650 -575);
WIRE 16 -1 (50 825)(50 750);
WIRE 16 -1 (200 1300)(200 1225);
WIRE 16 -1 (1725 675)(1725 550);
WIRE 16 -1 (1725 775)(1725 675);
WIRE 16 -1 (1575 675)(1725 675);
WIRE 16 -1 (1725 825)(1725 775);
WIRE 16 -1 (1575 775)(1725 775);
WIRE 16 -1 (1575 825)(1725 825);
WIRE 16 -1 (-225 2150)(-225 2075);
WIRE 16 -1 (200 2075)(200 2175);
WIRE 16 -1 (2100 550)(2100 650);
WIRE 16 -1 (3700 575)(3700 700);
WIRE 16 -1 (4425 700)(3700 700);
WIRE 16 -1 (3700 700)(3700 850);
WIRE 16 -1 (4425 875)(4425 700);
WIRE 16 -1 (3225 2100)(3225 2150);
WIRE 16 -1 (3325 3550)(3325 3600);
WIRE 16 -1 (3325 3550)(3675 3550);
WIRE 16 -1 (3325 3550)(3325 3400);
WIRE 16 -1 (4075 3550)(3675 3550);
WIRE 16 -1 (3675 3400)(3675 3550);
WIRE 16 -1 (4075 3400)(4075 3550);
WIRE 16 -1 (3850 1350)(3850 1425);
WIRE 16 -1 (5250 1450)(5250 1225);
WIRE 16 -1 (5250 1225)(4425 1225);
WIRE 16 -1 (5250 -75)(5250 1225);
WIRE 16 -1 (4850 -75)(5250 -75);
WIRE 16 -1 (3700 1225)(4425 1225);
WIRE 16 -1 (4425 1075)(4425 1225);
WIRE 16 -1 (1575 1225)(3700 1225);
WIRE 16 -1 (3700 1050)(3700 1225);
WIRE 16 -1 (3325 2875)(3325 2900);
WIRE 16 -1 (3325 2900)(3675 2900);
WIRE 16 -1 (3325 3200)(3325 2900);
WIRE 16 -1 (3675 2900)(4075 2900);
WIRE 16 -1 (3675 3200)(3675 2900);
WIRE 16 -1 (4075 3200)(4075 2900);
WIRE 16 -1 (-825 1925)(-825 1675);
WIRE 16 -1 (-825 1675)(-600 1675);
WIRE 16 -1 (-600 675)(-600 1675);
WIRE 16 -1 (-250 1675)(-600 1675);
WIRE 16 -1 (-1700 2650)(-1700 2450);
WIRE 16 -1 (-1350 2450)(-1700 2450);
WIRE 16 -1 (-1350 2450)(-1350 1450);
WIRE 16 -1 (-225 2450)(-1350 2450);
WIRE 16 -1 (-225 2450)(200 2450);
WIRE 16 -1 (-225 2350)(-225 2450);
WIRE 16 -1 (-1150 1450)(-1350 1450);
WIRE 16 -1 (200 2450)(825 2450);
WIRE 16 -1 (200 2375)(200 2450);
WIRE 16 -1 (825 1225)(825 2450);
WIRE 16 -1 (975 1225)(825 1225);
WIRE 3 682 (4000 3500)(4000 2800);
WIRE 3 682 (3250 3500)(4000 3500);
WIRE 3 682 (4000 2800)(3250 2800);
WIRE 3 682 (3250 2800)(3250 3500);
WIRE 16 2175 (3150 2475)(3150 3800);
WIRE 16 2175 (5275 3800)(3150 3800);
WIRE 16 2175 (5275 2475)(3150 2475);
WIRE 16 2175 (5275 2475)(5275 3800);
WIRE 3 682 (-1075 -25)(-2125 -25);
WIRE 3 682 (-1075 175)(-1075 -25);
WIRE 3 682 (-2125 -25)(-2125 175);
WIRE 3 682 (-2125 175)(-1075 175);
WIRE 16 -1 (-900 50)(-1625 50);
FORCEPROP 2 LAST SIG_NAME PWRGD_PVDDQ_ABC_R
J 0
(-1569 76);
DISPLAY 0.617021 (-1569 76);
PAINT ORANGE (-1569 76);
WIRE 16 -1 (2100 850)(2100 1125);
WIRE 16 -1 (1575 1125)(2100 1125);
FORCEPROP 2 LAST SIG_NAME VR_PVTT_ABC_VREF
J 0
(1643 1135);
DISPLAY 0.617021 (1643 1135);
PAINT ORANGE (1643 1135);
FORCEPROP 2 LASTPROP $XRERR UNIQUE?
J 0
(1403 1135);
DISPLAY 0.638298 (1403 1135);
PAINT MONO (1403 1135);
DISPLAY INVISIBLE (1403 1135);
WIRE 16 273 (675 3525)(1825 3525);
WIRE 16 273 (675 3425)(675 3525);
WIRE 16 273 (675 2925)(675 3425);
WIRE 16 273 (1825 2925)(675 2925);
WIRE 16 273 (675 3425)(1825 3425);
WIRE 16 273 (1825 3525)(1825 3425);
WIRE 16 273 (1825 3425)(1825 2925);
WIRE 16 -1 (975 725)(750 725);
WIRE 16 -1 (750 725)(750 1675);
WIRE 16 -1 (200 1500)(200 1675);
WIRE 16 -1 (750 1675)(200 1675);
WIRE 16 -1 (-50 1675)(200 1675);
FORCEPROP 2 LAST SIG_NAME VR_PVTT_ABC_BIAS
J 0
(33 1695);
DISPLAY 0.617021 (33 1695);
PAINT ORANGE (33 1695);
FORCEPROP 2 LASTPROP $XRERR UNIQUE?
J 0
(-207 1695);
DISPLAY 0.638298 (-207 1695);
PAINT MONO (-207 1695);
DISPLAY INVISIBLE (-207 1695);
WIRE 16 -1 (-650 -375)(-650 50);
WIRE 16 -1 (-700 50)(-650 50);
WIRE 16 -1 (-600 50)(-650 50);
WIRE 16 -1 (-600 50)(-600 475);
WIRE 16 -1 (300 50)(-600 50);
WIRE 16 -1 (300 975)(300 50);
WIRE 16 -1 (975 975)(300 975);
FORCEPROP 2 LAST SIG_NAME FM_PVTT_ABC_EN_R
J 0
(-301 65);
DISPLAY 0.617021 (-301 65);
PAINT ORANGE (-301 65);
FORCEPROP 2 LASTPROP $XRERR UNIQUE?
J 0
(-541 65);
DISPLAY 0.638298 (-541 65);
PAINT MONO (-541 65);
DISPLAY INVISIBLE (-541 65);
WIRE 16 2175 (-350 1150)(600 1150);
WIRE 16 2175 (600 1150)(600 2750);
WIRE 16 2175 (-350 1150)(-350 2750);
WIRE 16 2175 (-350 2750)(600 2750);
WIRE 16 -1 (5050 1725)(4450 1725);
FORCEPROP 2 LAST SIG_NAME PWRGD_PVTT_CPU0
J 0
(4548 1735);
DISPLAY 0.617021 (4548 1735);
PAINT ORANGE (4548 1735);
WIRE 16 -1 (700 -75)(4550 -75);
FORCEPROP 2 LAST SIG_NAME VR_PVTT_ABC_SNS
J 0
(752 -70);
DISPLAY 0.617021 (752 -70);
PAINT ORANGE (752 -70);
FORCEPROP 2 LASTPROP $XRERR UNIQUE?
J 0
(512 -70);
DISPLAY 0.638298 (512 -70);
PAINT MONO (512 -70);
DISPLAY INVISIBLE (512 -70);
WIRE 16 -1 (700 875)(700 -75);
WIRE 16 -1 (975 875)(700 875);
WIRE 16 2175 (1775 450)(1775 1575);
WIRE 16 2175 (2575 450)(1775 450);
WIRE 16 2175 (1775 1575)(2575 1575);
WIRE 16 2175 (2575 1575)(2575 450);
WIRE 16 -1 (-775 1450)(-950 1450);
WIRE 16 -1 (50 1025)(50 1075);
WIRE 16 -1 (50 1075)(975 1075);
WIRE 16 -1 (-775 1075)(-775 1450);
WIRE 16 -1 (-775 1075)(50 1075);
FORCEPROP 2 LAST SIG_NAME VSENSE_PVDDQ_ABC_VTT
J 0
(-341 1085);
DISPLAY 0.617021 (-341 1085);
PAINT ORANGE (-341 1085);
FORCEPROP 2 LASTPROP $XRERR UNIQUE?
J 0
(-581 1085);
DISPLAY 0.638298 (-581 1085);
PAINT MONO (-581 1085);
DISPLAY INVISIBLE (-581 1085);
WIRE 16 -1 (1575 925)(3225 925);
WIRE 16 -1 (3850 1625)(3850 1725);
WIRE 16 -1 (4250 1725)(3850 1725);
WIRE 16 -1 (3225 925)(3225 1725);
WIRE 16 -1 (3225 1725)(3225 1900);
WIRE 16 -1 (3225 1725)(3850 1725);
FORCEPROP 2 LAST SIG_NAME PWRGD_PVTT_ABC_CPU0_R
J 0
(3273 1735);
DISPLAY 0.617021 (3273 1735);
PAINT ORANGE (3273 1735);
FORCEPROP 2 LASTPROP $XRERR UNIQUE?
J 0
(3033 1735);
DISPLAY 0.638298 (3033 1735);
PAINT MONO (3033 1735);
DISPLAY INVISIBLE (3033 1735);
WIRE 3 682 (4350 1150)(4350 600);
WIRE 3 682 (5150 1150)(4350 1150);
WIRE 3 682 (4350 600)(5150 600);
WIRE 3 682 (5150 600)(5150 1150);
WIRE 16 2175 (4925 -525)(4925 50);
WIRE 16 2175 (4275 50)(4925 50);
WIRE 16 2175 (4275 -525)(4925 -525);
WIRE 16 2175 (4275 -525)(4275 50);
DOT 1 (3675 3550);
DOT 1 (3675 2900);
DOT 1 (3325 2900);
DOT 1 (4425 1225);
DOT 1 (5250 1225);
DOT 1 (3850 1725);
DOT 1 (3325 3550);
DOT 1 (1825 3425);
DOT 1 (3700 1225);
DOT 1 (3225 1725);
DOT 1 (3700 700);
DOT 1 (675 3425);
DOT 1 (-225 2450);
DOT 1 (1725 775);
DOT 1 (1725 675);
DOT 1 (200 1675);
DOT 1 (50 1075);
DOT 1 (-1350 2450);
DOT 1 (-600 1675);
DOT 1 (-600 50);
DOT 1 (-650 50);
DOT 1 (200 2450);
FORCENOTE
TP FAB3 CHANGE CAP 0803
(3250 2725) 0;
DISPLAY LEFT (3250 2725);
DISPLAY 1.021277 (3250 2725);
PAINT RED (3250 2725);
FORCENOTE
PLACE BETWEEN DIMMS
(4388 3296) 0;
DISPLAY LEFT (4388 3296);
DISPLAY 1.021277 (4388 3296);
PAINT PURPLE (4388 3296);
FORCENOTE
TP FAB1 CHANGE RES TO CAP 0311
(4225 425) 0;
DISPLAY LEFT (4225 425);
DISPLAY 1.021277 (4225 425);
PAINT RED (4225 425);
FORCENOTE
CRTICAL: PLACE 0 OHM NEAR  VDDQ SENSE RESISTOR.
(-2055 1249) 0;
DISPLAY LEFT (-2055 1249);
PAINT PURPLE (-2055 1249);
FORCENOTE
DC TOL= +/-1.5%
(719 3260) 0;
DISPLAY LEFT (719 3260);
DISPLAY 0.808511 (719 3260);
PAINT PURPLE (719 3260);
FORCENOTE
VOUT=0.5 VDDQ
(719 3360) 0;
DISPLAY LEFT (719 3360);
DISPLAY 0.808511 (719 3360);
PAINT PURPLE (719 3360);
FORCENOTE
IOUT DI/DT=6A/US
(719 3010) 0;
DISPLAY LEFT (719 3010);
DISPLAY 0.808511 (719 3010);
PAINT PURPLE (719 3010);
FORCENOTE
BOM = MEM_VRD_VTT_ABC
(-2255 -1001) 0;
DISPLAY LEFT (-2255 -1001);
DISPLAY 1.255319 (-2255 -1001);
PAINT PURPLE (-2255 -1001);
FORCENOTE
ROOM = VTT_ABC_PWR_VR
(-2255 -926) 0;
DISPLAY LEFT (-2255 -926);
DISPLAY 1.255319 (-2255 -926);
PAINT PURPLE (-2255 -926);
FORCENOTE
TP FAB1 CHANGE CONNECTION 0303
(-2125 200) 0;
DISPLAY LEFT (-2125 200);
DISPLAY 1.021277 (-2125 200);
PAINT RED (-2125 200);
FORCENOTE
RIPPLE GUIDELINE= +/-1%
(719 3310) 0;
DISPLAY LEFT (719 3310);
DISPLAY 0.808511 (719 3310);
PAINT PURPLE (719 3310);
FORCENOTE
PVTT DDR SPECIFICATION:
(719 3460) 0;
DISPLAY LEFT (719 3460);
PAINT PURPLE (719 3460);
FORCENOTE
IOUT TDC=+/-1.4A
(719 3110) 0;
DISPLAY LEFT (719 3110);
DISPLAY 0.808511 (719 3110);
PAINT PURPLE (719 3110);
FORCENOTE
IOUT PEAK=+-/1.4A
(719 3160) 0;
DISPLAY LEFT (719 3160);
DISPLAY 0.808511 (719 3160);
PAINT PURPLE (719 3160);
FORCENOTE
AC & RIPPLE=+3.5/-7.3%
(719 3210) 0;
DISPLAY LEFT (719 3210);
DISPLAY 0.808511 (719 3210);
PAINT PURPLE (719 3210);
FORCENOTE
IOUT STEP=+ 1.523A / - 1.546A
(719 3060) 0;
DISPLAY LEFT (719 3060);
DISPLAY 0.808511 (719 3060);
PAINT PURPLE (719 3060);
QUIT
